FILE_TYPE = MACRO_DRAWING;
SET COLOR_WIRE YELLOW;
SET COLOR_PROP ORANGE;
SET COLOR_DOT WHITE;
SET COLOR_ARC YELLOW;
SET COLOR_BODY GREEN;
SET COLOR_NOTE PURPLE;
SET PROP_DISPLAY VALUE;
SET PAGE_NUMBER P10;
SET PATH_NUMBER P579;
FORCEADD UNIVERSAL_POWER..1
(-7300 3200);
FORCEPROP 3 LASTPIN (-7300 3150) SIG_NAME P12V_AUX\g
J 0
(-7290 3160);
DISPLAY 0.659574 (-7290 3160);
PAINT MONO (-7290 3160);
DISPLAY INVISIBLE (-7290 3160);
FORCEPROP 1 LAST HDL_POWER P12V_AUX
J 1
(-7300 3250);
DISPLAY 0.702128 (-7300 3250);
PAINT GREEN (-7300 3250);
FORCEPROP 1 LAST PATH I173
J 0
(-7250 3225);
DISPLAY 0.872340 (-7250 3225);
PAINT AQUA (-7250 3225);
DISPLAY INVISIBLE (-7250 3225);
FORCEPROP 2 LAST CDS_LIB logical_power
J 0
(-7300 3200);
DISPLAY INVISIBLE (-7300 3200);
FORCEADD UNIVERSAL_GND..1
(-9300 -1700);
FORCEPROP 3 LASTPIN (-9300 -1650) SIG_NAME GND\g
J 0
(-9290 -1640);
DISPLAY 0.659574 (-9290 -1640);
PAINT MONO (-9290 -1640);
DISPLAY INVISIBLE (-9290 -1640);
FORCEPROP 1 LAST PATH I174
J 0
(-9225 -1700);
DISPLAY 0.872340 (-9225 -1700);
PAINT AQUA (-9225 -1700);
DISPLAY INVISIBLE (-9225 -1700);
FORCEPROP 1 LAST HDL_POWER GND
J 1
(-9275 -1775);
DISPLAY 0.702128 (-9275 -1775);
PAINT GREEN (-9275 -1775);
DISPLAY INVISIBLE (-9275 -1775);
FORCEPROP 2 LAST CDS_LIB logical_power
J 0
(-9300 -1700);
DISPLAY INVISIBLE (-9300 -1700);
FORCEADD UNIVERSAL_GND..1
(-7300 -1700);
FORCEPROP 3 LASTPIN (-7300 -1650) SIG_NAME GND\g
J 0
(-7290 -1640);
DISPLAY 0.659574 (-7290 -1640);
PAINT MONO (-7290 -1640);
DISPLAY INVISIBLE (-7290 -1640);
FORCEPROP 1 LAST PATH I175
J 0
(-7225 -1700);
DISPLAY 0.872340 (-7225 -1700);
PAINT AQUA (-7225 -1700);
DISPLAY INVISIBLE (-7225 -1700);
FORCEPROP 1 LAST HDL_POWER GND
J 1
(-7275 -1775);
DISPLAY 0.702128 (-7275 -1775);
PAINT GREEN (-7275 -1775);
DISPLAY INVISIBLE (-7275 -1775);
FORCEPROP 2 LAST CDS_LIB logical_power
J 0
(-7300 -1700);
DISPLAY INVISIBLE (-7300 -1700);
FORCEADD OFFPAGE..6
(-11175 2700);
FORCEPROP 2 LAST $XR0 14 
J 0
(-11424 2700);
DISPLAY 0.638298 (-11424 2700);
PAINT MONO (-11424 2700);
FORCEPROP 2 LAST PATH I188
J 0
(-11125 2775);
DISPLAY 1.021277 (-11125 2775);
DISPLAY INVISIBLE (-11125 2775);
FORCEPROP 1 LAST COMMENT_BODY TRUE
J 0
(-11075 2625);
DISPLAY 0.872340 (-11075 2625);
PAINT PEACH (-11075 2625);
DISPLAY INVISIBLE (-11075 2625);
FORCEPROP 1 LAST OFFPAGE TRUE
J 0
(-10850 2575);
DISPLAY 0.872340 (-10850 2575);
PAINT GREEN (-10850 2575);
DISPLAY INVISIBLE (-10850 2575);
FORCEPROP 2 LAST CDS_LIB standard
J 0
(-11175 2700);
DISPLAY INVISIBLE (-11175 2700);
FORCEADD OFFPAGE..1
(-11175 2750);
FORCEPROP 2 LAST $XR0 14 
J 0
(-11396 2750);
DISPLAY 0.638298 (-11396 2750);
PAINT MONO (-11396 2750);
FORCEPROP 2 LAST PATH I189
J 0
(-11125 2825);
DISPLAY 1.021277 (-11125 2825);
DISPLAY INVISIBLE (-11125 2825);
FORCEPROP 1 LAST COMMENT_BODY TRUE
J 0
(-11050 2650);
DISPLAY 0.872340 (-11050 2650);
PAINT PEACH (-11050 2650);
DISPLAY INVISIBLE (-11050 2650);
FORCEPROP 1 LAST OFFPAGE TRUE
J 0
(-10850 2625);
DISPLAY 0.872340 (-10850 2625);
PAINT GREEN (-10850 2625);
DISPLAY INVISIBLE (-10850 2625);
FORCEPROP 2 LAST CDS_LIB standard
J 0
(-11175 2750);
DISPLAY INVISIBLE (-11175 2750);
FORCEADD OFFPAGE..1
(-11175 2300);
FORCEPROP 2 LAST $XR0 11 
J 0
(-11396 2300);
DISPLAY 0.638298 (-11396 2300);
PAINT MONO (-11396 2300);
FORCEPROP 2 LAST $XR1 13 
J 0
(-11486 2300);
DISPLAY 0.638298 (-11486 2300);
PAINT MONO (-11486 2300);
FORCEPROP 2 LAST PATH I190
J 0
(-11350 2350);
DISPLAY 1.021277 (-11350 2350);
DISPLAY INVISIBLE (-11350 2350);
FORCEPROP 1 LAST COMMENT_BODY TRUE
J 0
(-11050 2200);
DISPLAY 0.872340 (-11050 2200);
PAINT PEACH (-11050 2200);
DISPLAY INVISIBLE (-11050 2200);
FORCEPROP 1 LAST OFFPAGE TRUE
J 0
(-10850 2175);
DISPLAY 0.872340 (-10850 2175);
PAINT GREEN (-10850 2175);
DISPLAY INVISIBLE (-10850 2175);
FORCEPROP 2 LAST CDS_LIB standard
J 0
(-11175 2300);
DISPLAY INVISIBLE (-11175 2300);
FORCEADD OFFPAGE..1
(-11175 -200);
FORCEPROP 2 LAST $XR0 11 
J 0
(-11396 -200);
DISPLAY 0.638298 (-11396 -200);
PAINT MONO (-11396 -200);
FORCEPROP 2 LAST $XR1 15 
J 0
(-11486 -200);
DISPLAY 0.638298 (-11486 -200);
PAINT MONO (-11486 -200);
FORCEPROP 2 LAST $XR2 10 
J 0
(-11576 -200);
DISPLAY 0.638298 (-11576 -200);
PAINT MONO (-11576 -200);
FORCEPROP 2 LAST PATH I225
J 0
(-11375 -150);
DISPLAY 1.021277 (-11375 -150);
DISPLAY INVISIBLE (-11375 -150);
FORCEPROP 1 LAST COMMENT_BODY TRUE
J 0
(-11050 -300);
DISPLAY 0.872340 (-11050 -300);
PAINT PEACH (-11050 -300);
DISPLAY INVISIBLE (-11050 -300);
FORCEPROP 1 LAST OFFPAGE TRUE
J 0
(-10850 -325);
DISPLAY 0.872340 (-10850 -325);
PAINT GREEN (-10850 -325);
DISPLAY INVISIBLE (-10850 -325);
FORCEPROP 2 LAST CDS_LIB standard
J 0
(-11175 -200);
DISPLAY INVISIBLE (-11175 -200);
FORCEADD OFFPAGE..5
(-11175 -250);
FORCEPROP 2 LAST $XR0 11 
J 0
(-11429 -250);
DISPLAY 0.638298 (-11429 -250);
PAINT MONO (-11429 -250);
FORCEPROP 2 LAST $XR3 35 
J 0
(-11699 -250);
DISPLAY 0.638298 (-11699 -250);
PAINT MONO (-11699 -250);
FORCEPROP 2 LAST $XR2 28 
J 0
(-11609 -250);
DISPLAY 0.638298 (-11609 -250);
PAINT MONO (-11609 -250);
FORCEPROP 2 LAST $XR1 13 
J 0
(-11519 -250);
DISPLAY 0.638298 (-11519 -250);
PAINT MONO (-11519 -250);
FORCEPROP 2 LAST PATH I226
J 0
(-11125 -175);
DISPLAY 1.021277 (-11125 -175);
DISPLAY INVISIBLE (-11125 -175);
FORCEPROP 1 LAST COMMENT_BODY TRUE
J 0
(-11075 -325);
DISPLAY 0.872340 (-11075 -325);
PAINT PEACH (-11075 -325);
DISPLAY INVISIBLE (-11075 -325);
FORCEPROP 1 LAST OFFPAGE TRUE
J 0
(-10850 -375);
DISPLAY 0.872340 (-10850 -375);
PAINT GREEN (-10850 -375);
DISPLAY INVISIBLE (-10850 -375);
FORCEPROP 2 LAST CDS_LIB standard
J 0
(-11175 -250);
DISPLAY INVISIBLE (-11175 -250);
FORCEADD OFFPAGE..4
(-5925 1550);
FORCEPROP 2 LAST $XR0 44 
J 0
(-5739 1550);
DISPLAY 0.638298 (-5739 1550);
PAINT MONO (-5739 1550);
FORCEPROP 2 LAST $XR1 46 
J 0
(-5649 1550);
DISPLAY 0.638298 (-5649 1550);
PAINT MONO (-5649 1550);
FORCEPROP 2 LAST PATH I232
J 0
(-5725 1600);
DISPLAY 1.021277 (-5725 1600);
DISPLAY INVISIBLE (-5725 1600);
FORCEPROP 1 LAST COMMENT_BODY TRUE
J 0
(-5950 1450);
DISPLAY 0.872340 (-5950 1450);
PAINT PEACH (-5950 1450);
DISPLAY INVISIBLE (-5950 1450);
FORCEPROP 1 LAST OFFPAGE TRUE
J 0
(-5600 1425);
DISPLAY 0.872340 (-5600 1425);
PAINT GREEN (-5600 1425);
DISPLAY INVISIBLE (-5600 1425);
FORCEPROP 2 LAST CDS_LIB standard
J 0
(-5925 1550);
DISPLAY INVISIBLE (-5925 1550);
FORCEADD OFFPAGE..2
(-5925 1500);
FORCEPROP 2 LAST $XR0 44 
J 0
(-5736 1500);
DISPLAY 0.638298 (-5736 1500);
PAINT MONO (-5736 1500);
FORCEPROP 2 LAST PATH I233
J 0
(-5725 1550);
DISPLAY 1.021277 (-5725 1550);
DISPLAY INVISIBLE (-5725 1550);
FORCEPROP 1 LAST COMMENT_BODY TRUE
J 0
(-5970 1405);
DISPLAY 0.872340 (-5970 1405);
PAINT PEACH (-5970 1405);
DISPLAY INVISIBLE (-5970 1405);
FORCEPROP 1 LAST OFFPAGE TRUE
J 0
(-5600 1375);
DISPLAY 0.872340 (-5600 1375);
PAINT GREEN (-5600 1375);
DISPLAY INVISIBLE (-5600 1375);
FORCEPROP 2 LAST CDS_LIB standard
J 0
(-5925 1500);
DISPLAY INVISIBLE (-5925 1500);
FORCEADD OFFPAGE..2
(-5925 1450);
FORCEPROP 2 LAST $XR0 44 
J 0
(-5736 1450);
DISPLAY 0.638298 (-5736 1450);
PAINT MONO (-5736 1450);
FORCEPROP 2 LAST PATH I234
J 0
(-5725 1500);
DISPLAY 1.021277 (-5725 1500);
DISPLAY INVISIBLE (-5725 1500);
FORCEPROP 1 LAST COMMENT_BODY TRUE
J 0
(-5970 1355);
DISPLAY 0.872340 (-5970 1355);
PAINT PEACH (-5970 1355);
DISPLAY INVISIBLE (-5970 1355);
FORCEPROP 1 LAST OFFPAGE TRUE
J 0
(-5600 1325);
DISPLAY 0.872340 (-5600 1325);
PAINT GREEN (-5600 1325);
DISPLAY INVISIBLE (-5600 1325);
FORCEPROP 2 LAST CDS_LIB standard
J 0
(-5925 1450);
DISPLAY INVISIBLE (-5925 1450);
FORCEADD OFFPAGE..2
(-5925 1600);
FORCEPROP 2 LAST $XR0 44 
J 0
(-5736 1600);
DISPLAY 0.638298 (-5736 1600);
PAINT MONO (-5736 1600);
FORCEPROP 2 LAST $XR1 46 
J 0
(-5646 1600);
DISPLAY 0.638298 (-5646 1600);
PAINT MONO (-5646 1600);
FORCEPROP 2 LAST PATH I235
J 0
(-5725 1650);
DISPLAY 1.021277 (-5725 1650);
DISPLAY INVISIBLE (-5725 1650);
FORCEPROP 1 LAST COMMENT_BODY TRUE
J 0
(-5970 1505);
DISPLAY 0.872340 (-5970 1505);
PAINT PEACH (-5970 1505);
DISPLAY INVISIBLE (-5970 1505);
FORCEPROP 1 LAST OFFPAGE TRUE
J 0
(-5600 1475);
DISPLAY 0.872340 (-5600 1475);
PAINT GREEN (-5600 1475);
DISPLAY INVISIBLE (-5600 1475);
FORCEPROP 2 LAST CDS_LIB standard
J 0
(-5925 1600);
DISPLAY INVISIBLE (-5925 1600);
FORCEADD OFFPAGE..2
(-5925 1650);
FORCEPROP 2 LAST $XR0 44 
J 0
(-5736 1650);
DISPLAY 0.638298 (-5736 1650);
PAINT MONO (-5736 1650);
FORCEPROP 2 LAST PATH I236
J 0
(-5725 1700);
DISPLAY 1.021277 (-5725 1700);
DISPLAY INVISIBLE (-5725 1700);
FORCEPROP 1 LAST COMMENT_BODY TRUE
J 0
(-5970 1555);
DISPLAY 0.872340 (-5970 1555);
PAINT PEACH (-5970 1555);
DISPLAY INVISIBLE (-5970 1555);
FORCEPROP 1 LAST OFFPAGE TRUE
J 0
(-5600 1525);
DISPLAY 0.872340 (-5600 1525);
PAINT GREEN (-5600 1525);
DISPLAY INVISIBLE (-5600 1525);
FORCEPROP 2 LAST CDS_LIB standard
J 0
(-5925 1650);
DISPLAY INVISIBLE (-5925 1650);
FORCEADD OFFPAGE..2
(-5925 1700);
FORCEPROP 2 LAST $XR1 46 
J 0
(-5646 1700);
DISPLAY 0.638298 (-5646 1700);
PAINT MONO (-5646 1700);
FORCEPROP 2 LAST $XR0 44 
J 0
(-5736 1700);
DISPLAY 0.638298 (-5736 1700);
PAINT MONO (-5736 1700);
FORCEPROP 2 LAST PATH I237
J 0
(-5725 1750);
DISPLAY 1.021277 (-5725 1750);
DISPLAY INVISIBLE (-5725 1750);
FORCEPROP 1 LAST COMMENT_BODY TRUE
J 0
(-5970 1605);
DISPLAY 0.872340 (-5970 1605);
PAINT PEACH (-5970 1605);
DISPLAY INVISIBLE (-5970 1605);
FORCEPROP 1 LAST OFFPAGE TRUE
J 0
(-5600 1575);
DISPLAY 0.872340 (-5600 1575);
PAINT GREEN (-5600 1575);
DISPLAY INVISIBLE (-5600 1575);
FORCEPROP 2 LAST CDS_LIB standard
J 0
(-5925 1700);
DISPLAY INVISIBLE (-5925 1700);
FORCEADD OFFPAGE..2
(-5925 1100);
FORCEPROP 2 LAST $XR1 13 
J 0
(-5646 1100);
DISPLAY 0.638298 (-5646 1100);
PAINT MONO (-5646 1100);
FORCEPROP 2 LAST $XR0 11 
J 0
(-5736 1100);
DISPLAY 0.638298 (-5736 1100);
PAINT MONO (-5736 1100);
FORCEPROP 2 LAST PATH I248
J 0
(-5750 1175);
DISPLAY 1.021277 (-5750 1175);
DISPLAY INVISIBLE (-5750 1175);
FORCEPROP 1 LAST COMMENT_BODY TRUE
J 0
(-5970 1005);
DISPLAY 0.872340 (-5970 1005);
PAINT PEACH (-5970 1005);
DISPLAY INVISIBLE (-5970 1005);
FORCEPROP 1 LAST OFFPAGE TRUE
J 0
(-5600 975);
DISPLAY 0.872340 (-5600 975);
PAINT GREEN (-5600 975);
DISPLAY INVISIBLE (-5600 975);
FORCEPROP 2 LAST CDS_LIB standard
J 0
(-5925 1100);
DISPLAY INVISIBLE (-5925 1100);
FORCEADD OFFPAGE..2
(-5925 1300);
FORCEPROP 2 LAST $XR0 11 
J 0
(-5736 1300);
DISPLAY 0.638298 (-5736 1300);
PAINT MONO (-5736 1300);
FORCEPROP 2 LAST $XR1 13 
J 0
(-5646 1300);
DISPLAY 0.638298 (-5646 1300);
PAINT MONO (-5646 1300);
FORCEPROP 2 LAST PATH I249
J 0
(-5750 1375);
DISPLAY 1.021277 (-5750 1375);
DISPLAY INVISIBLE (-5750 1375);
FORCEPROP 1 LAST COMMENT_BODY TRUE
J 0
(-5970 1205);
DISPLAY 0.872340 (-5970 1205);
PAINT PEACH (-5970 1205);
DISPLAY INVISIBLE (-5970 1205);
FORCEPROP 1 LAST OFFPAGE TRUE
J 0
(-5600 1175);
DISPLAY 0.872340 (-5600 1175);
PAINT GREEN (-5600 1175);
DISPLAY INVISIBLE (-5600 1175);
FORCEPROP 2 LAST CDS_LIB standard
J 0
(-5925 1300);
DISPLAY INVISIBLE (-5925 1300);
FORCEADD OFFPAGE..2
(-5925 1350);
FORCEPROP 2 LAST $XR0 13 
J 0
(-5736 1350);
DISPLAY 0.638298 (-5736 1350);
PAINT MONO (-5736 1350);
FORCEPROP 2 LAST PATH I250
J 0
(-5750 1425);
DISPLAY 1.021277 (-5750 1425);
DISPLAY INVISIBLE (-5750 1425);
FORCEPROP 1 LAST COMMENT_BODY TRUE
J 0
(-5970 1255);
DISPLAY 0.872340 (-5970 1255);
PAINT PEACH (-5970 1255);
DISPLAY INVISIBLE (-5970 1255);
FORCEPROP 1 LAST OFFPAGE TRUE
J 0
(-5600 1225);
DISPLAY 0.872340 (-5600 1225);
PAINT GREEN (-5600 1225);
DISPLAY INVISIBLE (-5600 1225);
FORCEPROP 2 LAST CDS_LIB standard
J 0
(-5925 1350);
DISPLAY INVISIBLE (-5925 1350);
FORCEADD OFFPAGE..4
(-5925 1200);
FORCEPROP 2 LAST $XR0 13 
J 0
(-5739 1200);
DISPLAY 0.638298 (-5739 1200);
PAINT MONO (-5739 1200);
FORCEPROP 2 LAST PATH I251
J 0
(-5750 1275);
DISPLAY 1.021277 (-5750 1275);
DISPLAY INVISIBLE (-5750 1275);
FORCEPROP 1 LAST COMMENT_BODY TRUE
J 0
(-5950 1100);
DISPLAY 0.872340 (-5950 1100);
PAINT PEACH (-5950 1100);
DISPLAY INVISIBLE (-5950 1100);
FORCEPROP 1 LAST OFFPAGE TRUE
J 0
(-5600 1075);
DISPLAY 0.872340 (-5600 1075);
PAINT GREEN (-5600 1075);
DISPLAY INVISIBLE (-5600 1075);
FORCEPROP 2 LAST CDS_LIB standard
J 0
(-5925 1200);
DISPLAY INVISIBLE (-5925 1200);
FORCEADD OFFPAGE..4
(-5925 1150);
FORCEPROP 2 LAST $XR0 13 
J 0
(-5739 1150);
DISPLAY 0.638298 (-5739 1150);
PAINT MONO (-5739 1150);
FORCEPROP 2 LAST PATH I252
J 0
(-5750 1225);
DISPLAY 1.021277 (-5750 1225);
DISPLAY INVISIBLE (-5750 1225);
FORCEPROP 1 LAST COMMENT_BODY TRUE
J 0
(-5950 1050);
DISPLAY 0.872340 (-5950 1050);
PAINT PEACH (-5950 1050);
DISPLAY INVISIBLE (-5950 1050);
FORCEPROP 1 LAST OFFPAGE TRUE
J 0
(-5600 1025);
DISPLAY 0.872340 (-5600 1025);
PAINT GREEN (-5600 1025);
DISPLAY INVISIBLE (-5600 1025);
FORCEPROP 2 LAST CDS_LIB standard
J 0
(-5925 1150);
DISPLAY INVISIBLE (-5925 1150);
FORCEADD OFFPAGE..2
(-5925 1050);
FORCEPROP 2 LAST $XR0 13 
J 0
(-5736 1050);
DISPLAY 0.638298 (-5736 1050);
PAINT MONO (-5736 1050);
FORCEPROP 2 LAST PATH I253
J 0
(-5750 1125);
DISPLAY 1.021277 (-5750 1125);
DISPLAY INVISIBLE (-5750 1125);
FORCEPROP 1 LAST COMMENT_BODY TRUE
J 0
(-5970 955);
DISPLAY 0.872340 (-5970 955);
PAINT PEACH (-5970 955);
DISPLAY INVISIBLE (-5970 955);
FORCEPROP 1 LAST OFFPAGE TRUE
J 0
(-5600 925);
DISPLAY 0.872340 (-5600 925);
PAINT GREEN (-5600 925);
DISPLAY INVISIBLE (-5600 925);
FORCEPROP 2 LAST CDS_LIB standard
J 0
(-5925 1050);
DISPLAY INVISIBLE (-5925 1050);
FORCEADD OFFPAGE..2
(-5925 1000);
FORCEPROP 2 LAST $XR0 13 
J 0
(-5736 1000);
DISPLAY 0.638298 (-5736 1000);
PAINT MONO (-5736 1000);
FORCEPROP 2 LAST PATH I254
J 0
(-5750 1075);
DISPLAY 1.021277 (-5750 1075);
DISPLAY INVISIBLE (-5750 1075);
FORCEPROP 1 LAST COMMENT_BODY TRUE
J 0
(-5970 905);
DISPLAY 0.872340 (-5970 905);
PAINT PEACH (-5970 905);
DISPLAY INVISIBLE (-5970 905);
FORCEPROP 1 LAST OFFPAGE TRUE
J 0
(-5600 875);
DISPLAY 0.872340 (-5600 875);
PAINT GREEN (-5600 875);
DISPLAY INVISIBLE (-5600 875);
FORCEPROP 2 LAST CDS_LIB standard
J 0
(-5925 1000);
DISPLAY INVISIBLE (-5925 1000);
FORCEADD OFFPAGE..4
(-5925 1250);
FORCEPROP 2 LAST $XR1 13 
J 0
(-5649 1250);
DISPLAY 0.638298 (-5649 1250);
PAINT MONO (-5649 1250);
FORCEPROP 2 LAST $XR0 11 
J 0
(-5739 1250);
DISPLAY 0.638298 (-5739 1250);
PAINT MONO (-5739 1250);
FORCEPROP 2 LAST PATH I255
J 0
(-5750 1325);
DISPLAY 1.021277 (-5750 1325);
DISPLAY INVISIBLE (-5750 1325);
FORCEPROP 1 LAST COMMENT_BODY TRUE
J 0
(-5950 1150);
DISPLAY 0.872340 (-5950 1150);
PAINT PEACH (-5950 1150);
DISPLAY INVISIBLE (-5950 1150);
FORCEPROP 1 LAST OFFPAGE TRUE
J 0
(-5600 1125);
DISPLAY 0.872340 (-5600 1125);
PAINT GREEN (-5600 1125);
DISPLAY INVISIBLE (-5600 1125);
FORCEPROP 2 LAST CDS_LIB standard
J 0
(-5925 1250);
DISPLAY INVISIBLE (-5925 1250);
FORCEADD OFFPAGE..4
(-5925 750);
FORCEPROP 2 LAST $XR0 11 
J 0
(-5739 750);
DISPLAY 0.638298 (-5739 750);
PAINT MONO (-5739 750);
FORCEPROP 2 LAST $XR1 34 
J 0
(-5649 750);
DISPLAY 0.638298 (-5649 750);
PAINT MONO (-5649 750);
FORCEPROP 2 LAST PATH I256
J 0
(-5725 800);
DISPLAY 1.021277 (-5725 800);
DISPLAY INVISIBLE (-5725 800);
FORCEPROP 1 LAST COMMENT_BODY TRUE
J 0
(-5950 650);
DISPLAY 0.872340 (-5950 650);
PAINT PEACH (-5950 650);
DISPLAY INVISIBLE (-5950 650);
FORCEPROP 1 LAST OFFPAGE TRUE
J 0
(-5600 625);
DISPLAY 0.872340 (-5600 625);
PAINT GREEN (-5600 625);
DISPLAY INVISIBLE (-5600 625);
FORCEPROP 2 LAST CDS_LIB standard
J 0
(-5925 750);
DISPLAY INVISIBLE (-5925 750);
FORCEADD OFFPAGE..4
(-5925 700);
FORCEPROP 2 LAST $XR0 11 
J 0
(-5739 700);
DISPLAY 0.638298 (-5739 700);
PAINT MONO (-5739 700);
FORCEPROP 2 LAST $XR1 34 
J 0
(-5649 700);
DISPLAY 0.638298 (-5649 700);
PAINT MONO (-5649 700);
FORCEPROP 2 LAST PATH I257
J 0
(-5725 750);
DISPLAY 1.021277 (-5725 750);
DISPLAY INVISIBLE (-5725 750);
FORCEPROP 1 LAST COMMENT_BODY TRUE
J 0
(-5950 600);
DISPLAY 0.872340 (-5950 600);
PAINT PEACH (-5950 600);
DISPLAY INVISIBLE (-5950 600);
FORCEPROP 1 LAST OFFPAGE TRUE
J 0
(-5600 575);
DISPLAY 0.872340 (-5600 575);
PAINT GREEN (-5600 575);
DISPLAY INVISIBLE (-5600 575);
FORCEPROP 2 LAST CDS_LIB standard
J 0
(-5925 700);
DISPLAY INVISIBLE (-5925 700);
FORCEADD OFFPAGE..4
(-5925 600);
FORCEPROP 2 LAST $XR1 34 
J 0
(-5649 600);
DISPLAY 0.638298 (-5649 600);
PAINT MONO (-5649 600);
FORCEPROP 2 LAST $XR0 11 
J 0
(-5739 600);
DISPLAY 0.638298 (-5739 600);
PAINT MONO (-5739 600);
FORCEPROP 2 LAST PATH I258
J 0
(-5725 650);
DISPLAY 1.021277 (-5725 650);
DISPLAY INVISIBLE (-5725 650);
FORCEPROP 1 LAST COMMENT_BODY TRUE
J 0
(-5950 500);
DISPLAY 0.872340 (-5950 500);
PAINT PEACH (-5950 500);
DISPLAY INVISIBLE (-5950 500);
FORCEPROP 1 LAST OFFPAGE TRUE
J 0
(-5600 475);
DISPLAY 0.872340 (-5600 475);
PAINT GREEN (-5600 475);
DISPLAY INVISIBLE (-5600 475);
FORCEPROP 2 LAST CDS_LIB standard
J 0
(-5925 600);
DISPLAY INVISIBLE (-5925 600);
FORCEADD OFFPAGE..2
(-5925 650);
FORCEPROP 2 LAST $XR0 11 
J 0
(-5736 650);
DISPLAY 0.638298 (-5736 650);
PAINT MONO (-5736 650);
FORCEPROP 2 LAST $XR1 34 
J 0
(-5646 650);
DISPLAY 0.638298 (-5646 650);
PAINT MONO (-5646 650);
FORCEPROP 2 LAST PATH I259
J 0
(-5725 700);
DISPLAY 1.021277 (-5725 700);
DISPLAY INVISIBLE (-5725 700);
FORCEPROP 1 LAST COMMENT_BODY TRUE
J 0
(-5970 555);
DISPLAY 0.872340 (-5970 555);
PAINT PEACH (-5970 555);
DISPLAY INVISIBLE (-5970 555);
FORCEPROP 1 LAST OFFPAGE TRUE
J 0
(-5600 525);
DISPLAY 0.872340 (-5600 525);
PAINT GREEN (-5600 525);
DISPLAY INVISIBLE (-5600 525);
FORCEPROP 2 LAST CDS_LIB standard
J 0
(-5925 650);
DISPLAY INVISIBLE (-5925 650);
FORCEADD OFFPAGE..4
(-5925 450);
FORCEPROP 2 LAST $XR0 11 
J 0
(-5739 450);
DISPLAY 0.638298 (-5739 450);
PAINT MONO (-5739 450);
FORCEPROP 2 LAST $XR1 12 
J 0
(-5649 450);
DISPLAY 0.638298 (-5649 450);
PAINT MONO (-5649 450);
FORCEPROP 2 LAST PATH I260
J 0
(-5750 525);
DISPLAY 1.021277 (-5750 525);
DISPLAY INVISIBLE (-5750 525);
FORCEPROP 1 LAST COMMENT_BODY TRUE
J 0
(-5950 350);
DISPLAY 0.872340 (-5950 350);
PAINT PEACH (-5950 350);
DISPLAY INVISIBLE (-5950 350);
FORCEPROP 1 LAST OFFPAGE TRUE
J 0
(-5600 325);
DISPLAY 0.872340 (-5600 325);
PAINT GREEN (-5600 325);
DISPLAY INVISIBLE (-5600 325);
FORCEPROP 2 LAST CDS_LIB standard
J 0
(-5925 450);
DISPLAY INVISIBLE (-5925 450);
FORCEADD OFFPAGE..2
(-5925 400);
FORCEPROP 2 LAST $XR1 12 
J 0
(-5646 400);
DISPLAY 0.638298 (-5646 400);
PAINT MONO (-5646 400);
FORCEPROP 2 LAST $XR0 11 
J 0
(-5736 400);
DISPLAY 0.638298 (-5736 400);
PAINT MONO (-5736 400);
FORCEPROP 2 LAST PATH I261
J 0
(-5750 475);
DISPLAY 1.021277 (-5750 475);
DISPLAY INVISIBLE (-5750 475);
FORCEPROP 1 LAST COMMENT_BODY TRUE
J 0
(-5970 305);
DISPLAY 0.872340 (-5970 305);
PAINT PEACH (-5970 305);
DISPLAY INVISIBLE (-5970 305);
FORCEPROP 1 LAST OFFPAGE TRUE
J 0
(-5600 275);
DISPLAY 0.872340 (-5600 275);
PAINT GREEN (-5600 275);
DISPLAY INVISIBLE (-5600 275);
FORCEPROP 2 LAST CDS_LIB standard
J 0
(-5925 400);
DISPLAY INVISIBLE (-5925 400);
FORCEADD OFFPAGE..4
(-5925 500);
FORCEPROP 2 LAST $XR0 11 
J 0
(-5739 500);
DISPLAY 0.638298 (-5739 500);
PAINT MONO (-5739 500);
FORCEPROP 2 LAST $XR1 12 
J 0
(-5649 500);
DISPLAY 0.638298 (-5649 500);
PAINT MONO (-5649 500);
FORCEPROP 2 LAST PATH I262
J 0
(-5750 575);
DISPLAY 1.021277 (-5750 575);
DISPLAY INVISIBLE (-5750 575);
FORCEPROP 1 LAST COMMENT_BODY TRUE
J 0
(-5950 400);
DISPLAY 0.872340 (-5950 400);
PAINT PEACH (-5950 400);
DISPLAY INVISIBLE (-5950 400);
FORCEPROP 1 LAST OFFPAGE TRUE
J 0
(-5600 375);
DISPLAY 0.872340 (-5600 375);
PAINT GREEN (-5600 375);
DISPLAY INVISIBLE (-5600 375);
FORCEPROP 2 LAST CDS_LIB standard
J 0
(-5925 500);
DISPLAY INVISIBLE (-5925 500);
FORCEADD OFFPAGE..4
(-5925 350);
FORCEPROP 2 LAST $XR1 12 
J 0
(-5649 350);
DISPLAY 0.638298 (-5649 350);
PAINT MONO (-5649 350);
FORCEPROP 2 LAST $XR0 11 
J 0
(-5739 350);
DISPLAY 0.638298 (-5739 350);
PAINT MONO (-5739 350);
FORCEPROP 2 LAST PATH I263
J 0
(-5750 425);
DISPLAY 1.021277 (-5750 425);
DISPLAY INVISIBLE (-5750 425);
FORCEPROP 1 LAST COMMENT_BODY TRUE
J 0
(-5950 250);
DISPLAY 0.872340 (-5950 250);
PAINT PEACH (-5950 250);
DISPLAY INVISIBLE (-5950 250);
FORCEPROP 1 LAST OFFPAGE TRUE
J 0
(-5600 225);
DISPLAY 0.872340 (-5600 225);
PAINT GREEN (-5600 225);
DISPLAY INVISIBLE (-5600 225);
FORCEPROP 2 LAST CDS_LIB standard
J 0
(-5925 350);
DISPLAY INVISIBLE (-5925 350);
FORCEADD OFFPAGE..4
(-5925 250);
FORCEPROP 2 LAST $XR1 13 
J 0
(-5649 250);
DISPLAY 0.638298 (-5649 250);
PAINT MONO (-5649 250);
FORCEPROP 2 LAST $XR0 11 
J 0
(-5739 250);
DISPLAY 0.638298 (-5739 250);
PAINT MONO (-5739 250);
FORCEPROP 2 LAST $XR2 35 
J 0
(-5559 250);
DISPLAY 0.638298 (-5559 250);
PAINT MONO (-5559 250);
FORCEPROP 1 LAST COMMENT_BODY TRUE
J 0
(-5950 150);
DISPLAY 0.872340 (-5950 150);
PAINT PEACH (-5950 150);
DISPLAY INVISIBLE (-5950 150);
FORCEPROP 1 LAST OFFPAGE TRUE
J 0
(-5600 125);
DISPLAY 0.872340 (-5600 125);
PAINT GREEN (-5600 125);
DISPLAY INVISIBLE (-5600 125);
FORCEPROP 2 LAST PATH I264
J 0
(-5750 325);
DISPLAY 1.021277 (-5750 325);
DISPLAY INVISIBLE (-5750 325);
FORCEPROP 2 LAST CDS_LIB standard
J 0
(-5925 250);
DISPLAY INVISIBLE (-5925 250);
FORCEADD OFFPAGE..2
(-5925 200);
FORCEPROP 2 LAST $XR2 35 
J 0
(-5556 200);
DISPLAY 0.638298 (-5556 200);
PAINT MONO (-5556 200);
FORCEPROP 2 LAST $XR1 13 
J 0
(-5646 200);
DISPLAY 0.638298 (-5646 200);
PAINT MONO (-5646 200);
FORCEPROP 2 LAST $XR0 11 
J 0
(-5736 200);
DISPLAY 0.638298 (-5736 200);
PAINT MONO (-5736 200);
FORCEPROP 2 LAST CDS_LIB standard
J 0
(-5925 200);
DISPLAY INVISIBLE (-5925 200);
FORCEPROP 1 LAST OFFPAGE TRUE
J 0
(-5600 75);
DISPLAY 0.872340 (-5600 75);
PAINT GREEN (-5600 75);
DISPLAY INVISIBLE (-5600 75);
FORCEPROP 1 LAST COMMENT_BODY TRUE
J 0
(-5970 105);
DISPLAY 0.872340 (-5970 105);
PAINT PEACH (-5970 105);
DISPLAY INVISIBLE (-5970 105);
FORCEPROP 2 LAST PATH I265
J 0
(-5750 275);
DISPLAY 1.021277 (-5750 275);
DISPLAY INVISIBLE (-5750 275);
FORCEADD OFFPAGE..3
(-5925 -350);
FORCEPROP 2 LAST $XR0 15 
J 0
(-5711 -350);
DISPLAY 0.638298 (-5711 -350);
PAINT MONO (-5711 -350);
FORCEPROP 2 LAST PATH I266
J 0
(-5725 -275);
DISPLAY 1.021277 (-5725 -275);
DISPLAY INVISIBLE (-5725 -275);
FORCEPROP 1 LAST COMMENT_BODY TRUE
J 0
(-5975 -450);
DISPLAY 0.872340 (-5975 -450);
PAINT PEACH (-5975 -450);
DISPLAY INVISIBLE (-5975 -450);
FORCEPROP 1 LAST OFFPAGE TRUE
J 0
(-5600 -475);
DISPLAY 0.872340 (-5600 -475);
PAINT GREEN (-5600 -475);
DISPLAY INVISIBLE (-5600 -475);
FORCEPROP 2 LAST CDS_LIB standard
J 0
(-5925 -350);
DISPLAY INVISIBLE (-5925 -350);
FORCEADD OFFPAGE..3
(-5925 -400);
FORCEPROP 2 LAST $XR0 15 
J 0
(-5711 -400);
DISPLAY 0.638298 (-5711 -400);
PAINT MONO (-5711 -400);
FORCEPROP 2 LAST PATH I267
J 0
(-5725 -325);
DISPLAY 1.021277 (-5725 -325);
DISPLAY INVISIBLE (-5725 -325);
FORCEPROP 1 LAST COMMENT_BODY TRUE
J 0
(-5975 -500);
DISPLAY 0.872340 (-5975 -500);
PAINT PEACH (-5975 -500);
DISPLAY INVISIBLE (-5975 -500);
FORCEPROP 1 LAST OFFPAGE TRUE
J 0
(-5600 -525);
DISPLAY 0.872340 (-5600 -525);
PAINT GREEN (-5600 -525);
DISPLAY INVISIBLE (-5600 -525);
FORCEPROP 2 LAST CDS_LIB standard
J 0
(-5925 -400);
DISPLAY INVISIBLE (-5925 -400);
FORCEADD OFFPAGE..3
(-5925 -650);
FORCEPROP 2 LAST $XR0 29 
J 0
(-5711 -650);
DISPLAY 0.638298 (-5711 -650);
PAINT MONO (-5711 -650);
FORCEPROP 2 LAST PATH I272
J 0
(-5725 -575);
DISPLAY 1.021277 (-5725 -575);
DISPLAY INVISIBLE (-5725 -575);
FORCEPROP 1 LAST COMMENT_BODY TRUE
J 0
(-5975 -750);
DISPLAY 0.872340 (-5975 -750);
PAINT PEACH (-5975 -750);
DISPLAY INVISIBLE (-5975 -750);
FORCEPROP 1 LAST OFFPAGE TRUE
J 0
(-5600 -775);
DISPLAY 0.872340 (-5600 -775);
PAINT GREEN (-5600 -775);
DISPLAY INVISIBLE (-5600 -775);
FORCEPROP 2 LAST CDS_LIB standard
J 0
(-5925 -650);
DISPLAY INVISIBLE (-5925 -650);
FORCEADD OFFPAGE..3
(-5925 -700);
FORCEPROP 2 LAST $XR0 29 
J 0
(-5711 -700);
DISPLAY 0.638298 (-5711 -700);
PAINT MONO (-5711 -700);
FORCEPROP 2 LAST PATH I273
J 0
(-5725 -625);
DISPLAY 1.021277 (-5725 -625);
DISPLAY INVISIBLE (-5725 -625);
FORCEPROP 1 LAST COMMENT_BODY TRUE
J 0
(-5975 -800);
DISPLAY 0.872340 (-5975 -800);
PAINT PEACH (-5975 -800);
DISPLAY INVISIBLE (-5975 -800);
FORCEPROP 1 LAST OFFPAGE TRUE
J 0
(-5600 -825);
DISPLAY 0.872340 (-5600 -825);
PAINT GREEN (-5600 -825);
DISPLAY INVISIBLE (-5600 -825);
FORCEPROP 2 LAST CDS_LIB standard
J 0
(-5925 -700);
DISPLAY INVISIBLE (-5925 -700);
FORCEADD OFFPAGE..4
R 2
(-11175 450);
FORCEPROP 2 LAST $XR0 32 
J 0
(-11396 450);
DISPLAY 0.638298 (-11396 450);
PAINT MONO (-11396 450);
FORCEPROP 2 LAST PATH I274
J 2
(-11375 500);
DISPLAY 1.021277 (-11375 500);
DISPLAY INVISIBLE (-11375 500);
FORCEPROP 1 LAST COMMENT_BODY TRUE
J 2
(-11150 350);
DISPLAY 0.872340 (-11150 350);
PAINT PEACH (-11150 350);
DISPLAY INVISIBLE (-11150 350);
FORCEPROP 1 LAST OFFPAGE TRUE
J 2
(-11500 325);
DISPLAY 0.872340 (-11500 325);
PAINT GREEN (-11500 325);
DISPLAY INVISIBLE (-11500 325);
FORCEPROP 2 LAST CDS_LIB standard
J 2
(-11175 450);
DISPLAY INVISIBLE (-11175 450);
FORCEADD OFFPAGE..4
R 2
(-11175 400);
FORCEPROP 2 LAST $XR0 32 
J 0
(-11396 400);
DISPLAY 0.638298 (-11396 400);
PAINT MONO (-11396 400);
FORCEPROP 2 LAST PATH I275
J 2
(-11375 450);
DISPLAY 1.021277 (-11375 450);
DISPLAY INVISIBLE (-11375 450);
FORCEPROP 1 LAST COMMENT_BODY TRUE
J 2
(-11150 300);
DISPLAY 0.872340 (-11150 300);
PAINT PEACH (-11150 300);
DISPLAY INVISIBLE (-11150 300);
FORCEPROP 1 LAST OFFPAGE TRUE
J 2
(-11500 275);
DISPLAY 0.872340 (-11500 275);
PAINT GREEN (-11500 275);
DISPLAY INVISIBLE (-11500 275);
FORCEPROP 2 LAST CDS_LIB standard
J 2
(-11175 400);
DISPLAY INVISIBLE (-11175 400);
FORCEADD OFFPAGE..4
R 2
(-11175 500);
FORCEPROP 2 LAST $XR0 32 
J 0
(-11396 500);
DISPLAY 0.638298 (-11396 500);
PAINT MONO (-11396 500);
FORCEPROP 2 LAST PATH I276
J 2
(-11375 550);
DISPLAY 1.021277 (-11375 550);
DISPLAY INVISIBLE (-11375 550);
FORCEPROP 1 LAST COMMENT_BODY TRUE
J 2
(-11150 400);
DISPLAY 0.872340 (-11150 400);
PAINT PEACH (-11150 400);
DISPLAY INVISIBLE (-11150 400);
FORCEPROP 1 LAST OFFPAGE TRUE
J 2
(-11500 375);
DISPLAY 0.872340 (-11500 375);
PAINT GREEN (-11500 375);
DISPLAY INVISIBLE (-11500 375);
FORCEPROP 2 LAST CDS_LIB standard
J 2
(-11175 500);
DISPLAY INVISIBLE (-11175 500);
FORCEADD OFFPAGE..2
R 2
(-11175 350);
FORCEPROP 2 LAST $XR0 32 
J 0
(-11429 350);
DISPLAY 0.638298 (-11429 350);
PAINT MONO (-11429 350);
FORCEPROP 2 LAST PATH I277
J 2
(-11375 400);
DISPLAY 1.021277 (-11375 400);
DISPLAY INVISIBLE (-11375 400);
FORCEPROP 1 LAST COMMENT_BODY TRUE
J 2
(-11130 255);
DISPLAY 0.872340 (-11130 255);
PAINT PEACH (-11130 255);
DISPLAY INVISIBLE (-11130 255);
FORCEPROP 1 LAST OFFPAGE TRUE
J 2
(-11500 225);
DISPLAY 0.872340 (-11500 225);
PAINT GREEN (-11500 225);
DISPLAY INVISIBLE (-11500 225);
FORCEPROP 2 LAST CDS_LIB standard
J 2
(-11175 350);
DISPLAY INVISIBLE (-11175 350);
FORCEADD OFFPAGE..5
(-11175 -50);
FORCEPROP 2 LAST $XR1 13 
J 0
(-11519 -50);
DISPLAY 0.638298 (-11519 -50);
PAINT MONO (-11519 -50);
FORCEPROP 2 LAST $XR0 11 
J 0
(-11429 -50);
DISPLAY 0.638298 (-11429 -50);
PAINT MONO (-11429 -50);
FORCEPROP 2 LAST $XR3 28 
J 0
(-11699 -50);
DISPLAY 0.638298 (-11699 -50);
PAINT MONO (-11699 -50);
FORCEPROP 2 LAST $XR4 34 
J 0
(-11789 -50);
DISPLAY 0.638298 (-11789 -50);
PAINT MONO (-11789 -50);
FORCEPROP 2 LAST $XR2 22 
J 0
(-11609 -50);
DISPLAY 0.638298 (-11609 -50);
PAINT MONO (-11609 -50);
FORCEPROP 2 LAST PATH I279
J 0
(-11600 0);
DISPLAY 1.021277 (-11600 0);
DISPLAY INVISIBLE (-11600 0);
FORCEPROP 1 LAST COMMENT_BODY TRUE
J 0
(-11075 -125);
DISPLAY 0.872340 (-11075 -125);
PAINT PEACH (-11075 -125);
DISPLAY INVISIBLE (-11075 -125);
FORCEPROP 1 LAST OFFPAGE TRUE
J 0
(-10850 -175);
DISPLAY 0.872340 (-10850 -175);
PAINT GREEN (-10850 -175);
DISPLAY INVISIBLE (-10850 -175);
FORCEPROP 2 LAST CDS_LIB standard
J 0
(-11175 -50);
DISPLAY INVISIBLE (-11175 -50);
FORCEADD OFFPAGE..3
(-5925 1950);
FORCEPROP 2 LAST $XR0 12 
J 0
(-5711 1950);
DISPLAY 0.638298 (-5711 1950);
PAINT MONO (-5711 1950);
FORCEPROP 2 LAST PATH I281
J 0
(-5700 2000);
DISPLAY 1.021277 (-5700 2000);
DISPLAY INVISIBLE (-5700 2000);
FORCEPROP 1 LAST COMMENT_BODY TRUE
J 0
(-5975 1850);
DISPLAY 0.872340 (-5975 1850);
PAINT PEACH (-5975 1850);
DISPLAY INVISIBLE (-5975 1850);
FORCEPROP 1 LAST OFFPAGE TRUE
J 0
(-5600 1825);
DISPLAY 0.872340 (-5600 1825);
PAINT GREEN (-5600 1825);
DISPLAY INVISIBLE (-5600 1825);
FORCEPROP 2 LAST CDS_LIB standard
J 0
(-5925 1950);
DISPLAY INVISIBLE (-5925 1950);
FORCEADD OFFPAGE..3
(-5925 1900);
FORCEPROP 2 LAST $XR0 12 
J 0
(-5711 1900);
DISPLAY 0.638298 (-5711 1900);
PAINT MONO (-5711 1900);
FORCEPROP 2 LAST PATH I282
J 0
(-5700 1950);
DISPLAY 1.021277 (-5700 1950);
DISPLAY INVISIBLE (-5700 1950);
FORCEPROP 1 LAST COMMENT_BODY TRUE
J 0
(-5975 1800);
DISPLAY 0.872340 (-5975 1800);
PAINT PEACH (-5975 1800);
DISPLAY INVISIBLE (-5975 1800);
FORCEPROP 1 LAST OFFPAGE TRUE
J 0
(-5600 1775);
DISPLAY 0.872340 (-5600 1775);
PAINT GREEN (-5600 1775);
DISPLAY INVISIBLE (-5600 1775);
FORCEPROP 2 LAST CDS_LIB standard
J 0
(-5925 1900);
DISPLAY INVISIBLE (-5925 1900);
FORCEADD OFFPAGE..3
(-5925 2000);
FORCEPROP 2 LAST $XR0 12 
J 0
(-5711 2000);
DISPLAY 0.638298 (-5711 2000);
PAINT MONO (-5711 2000);
FORCEPROP 2 LAST PATH I283
J 0
(-5700 2050);
DISPLAY 1.021277 (-5700 2050);
DISPLAY INVISIBLE (-5700 2050);
FORCEPROP 1 LAST COMMENT_BODY TRUE
J 0
(-5975 1900);
DISPLAY 0.872340 (-5975 1900);
PAINT PEACH (-5975 1900);
DISPLAY INVISIBLE (-5975 1900);
FORCEPROP 1 LAST OFFPAGE TRUE
J 0
(-5600 1875);
DISPLAY 0.872340 (-5600 1875);
PAINT GREEN (-5600 1875);
DISPLAY INVISIBLE (-5600 1875);
FORCEPROP 2 LAST CDS_LIB standard
J 0
(-5925 2000);
DISPLAY INVISIBLE (-5925 2000);
FORCEADD OFFPAGE..3
(-5925 1850);
FORCEPROP 2 LAST $XR0 12 
J 0
(-5711 1850);
DISPLAY 0.638298 (-5711 1850);
PAINT MONO (-5711 1850);
FORCEPROP 2 LAST PATH I284
J 0
(-5700 1900);
DISPLAY 1.021277 (-5700 1900);
DISPLAY INVISIBLE (-5700 1900);
FORCEPROP 1 LAST COMMENT_BODY TRUE
J 0
(-5975 1750);
DISPLAY 0.872340 (-5975 1750);
PAINT PEACH (-5975 1750);
DISPLAY INVISIBLE (-5975 1750);
FORCEPROP 1 LAST OFFPAGE TRUE
J 0
(-5600 1725);
DISPLAY 0.872340 (-5600 1725);
PAINT GREEN (-5600 1725);
DISPLAY INVISIBLE (-5600 1725);
FORCEPROP 2 LAST CDS_LIB standard
J 0
(-5925 1850);
DISPLAY INVISIBLE (-5925 1850);
FORCEADD OFFPAGE..3
(-5925 2100);
FORCEPROP 2 LAST $XR0 12 
J 0
(-5711 2100);
DISPLAY 0.638298 (-5711 2100);
PAINT MONO (-5711 2100);
FORCEPROP 2 LAST PATH I286
J 0
(-5700 2150);
DISPLAY 1.021277 (-5700 2150);
DISPLAY INVISIBLE (-5700 2150);
FORCEPROP 1 LAST COMMENT_BODY TRUE
J 0
(-5975 2000);
DISPLAY 0.872340 (-5975 2000);
PAINT PEACH (-5975 2000);
DISPLAY INVISIBLE (-5975 2000);
FORCEPROP 1 LAST OFFPAGE TRUE
J 0
(-5600 1975);
DISPLAY 0.872340 (-5600 1975);
PAINT GREEN (-5600 1975);
DISPLAY INVISIBLE (-5600 1975);
FORCEPROP 2 LAST CDS_LIB standard
J 0
(-5925 2100);
DISPLAY INVISIBLE (-5925 2100);
FORCEADD OFFPAGE..2
(-5925 2200);
FORCEPROP 2 LAST $XR0 12 
J 0
(-5736 2200);
DISPLAY 0.638298 (-5736 2200);
PAINT MONO (-5736 2200);
FORCEPROP 2 LAST CDS_LIB standard
J 0
(-5925 2200);
DISPLAY INVISIBLE (-5925 2200);
FORCEPROP 2 LAST PATH I287
J 0
(-5750 2275);
DISPLAY 1.021277 (-5750 2275);
DISPLAY INVISIBLE (-5750 2275);
FORCEPROP 1 LAST COMMENT_BODY TRUE
J 0
(-5970 2105);
DISPLAY 0.872340 (-5970 2105);
PAINT PEACH (-5970 2105);
DISPLAY INVISIBLE (-5970 2105);
FORCEPROP 1 LAST OFFPAGE TRUE
J 0
(-5600 2075);
DISPLAY 0.872340 (-5600 2075);
PAINT GREEN (-5600 2075);
DISPLAY INVISIBLE (-5600 2075);
FORCEADD OFFPAGE..2
(-5925 2150);
FORCEPROP 2 LAST $XR0 12 
J 0
(-5736 2150);
DISPLAY 0.638298 (-5736 2150);
PAINT MONO (-5736 2150);
FORCEPROP 2 LAST PATH I288
J 0
(-5750 2225);
DISPLAY 1.021277 (-5750 2225);
DISPLAY INVISIBLE (-5750 2225);
FORCEPROP 1 LAST COMMENT_BODY TRUE
J 0
(-5970 2055);
DISPLAY 0.872340 (-5970 2055);
PAINT PEACH (-5970 2055);
DISPLAY INVISIBLE (-5970 2055);
FORCEPROP 1 LAST OFFPAGE TRUE
J 0
(-5600 2025);
DISPLAY 0.872340 (-5600 2025);
PAINT GREEN (-5600 2025);
DISPLAY INVISIBLE (-5600 2025);
FORCEPROP 2 LAST CDS_LIB standard
J 0
(-5925 2150);
DISPLAY INVISIBLE (-5925 2150);
FORCEADD OFFPAGE..5
(-11175 -350);
FORCEPROP 2 LAST $XR0 13 
J 0
(-11429 -350);
DISPLAY 0.638298 (-11429 -350);
PAINT MONO (-11429 -350);
FORCEPROP 2 LAST PATH I289
J 0
(-11350 -300);
DISPLAY 1.021277 (-11350 -300);
DISPLAY INVISIBLE (-11350 -300);
FORCEPROP 1 LAST COMMENT_BODY TRUE
J 0
(-11075 -425);
DISPLAY 0.872340 (-11075 -425);
PAINT PEACH (-11075 -425);
DISPLAY INVISIBLE (-11075 -425);
FORCEPROP 1 LAST OFFPAGE TRUE
J 0
(-10850 -475);
DISPLAY 0.872340 (-10850 -475);
PAINT GREEN (-10850 -475);
DISPLAY INVISIBLE (-10850 -475);
FORCEPROP 2 LAST CDS_LIB standard
J 0
(-11175 -350);
DISPLAY INVISIBLE (-11175 -350);
FORCEADD OFFPAGE..1
(-11175 -300);
FORCEPROP 2 LAST $XR0 13 
J 0
(-11426 -300);
DISPLAY 0.638298 (-11426 -300);
PAINT MONO (-11426 -300);
FORCEPROP 2 LAST PATH I290
J 0
(-11375 -250);
DISPLAY 1.021277 (-11375 -250);
DISPLAY INVISIBLE (-11375 -250);
FORCEPROP 1 LAST COMMENT_BODY TRUE
J 0
(-11050 -400);
DISPLAY 0.872340 (-11050 -400);
PAINT PEACH (-11050 -400);
DISPLAY INVISIBLE (-11050 -400);
FORCEPROP 1 LAST OFFPAGE TRUE
J 0
(-10850 -425);
DISPLAY 0.872340 (-10850 -425);
PAINT GREEN (-10850 -425);
DISPLAY INVISIBLE (-10850 -425);
FORCEPROP 2 LAST CDS_LIB standard
J 0
(-11175 -300);
DISPLAY INVISIBLE (-11175 -300);
FORCEADD OFFPAGE..5
(-11175 -650);
FORCEPROP 2 LAST $XR0 13 
J 0
(-11429 -650);
DISPLAY 0.638298 (-11429 -650);
PAINT MONO (-11429 -650);
FORCEPROP 2 LAST PATH I292
J 0
(-11600 -600);
DISPLAY 1.021277 (-11600 -600);
DISPLAY INVISIBLE (-11600 -600);
FORCEPROP 1 LAST COMMENT_BODY TRUE
J 0
(-11075 -725);
DISPLAY 0.872340 (-11075 -725);
PAINT GREEN (-11075 -725);
DISPLAY INVISIBLE (-11075 -725);
FORCEPROP 1 LAST OFFPAGE TRUE
J 0
(-10850 -775);
DISPLAY 0.872340 (-10850 -775);
DISPLAY INVISIBLE (-10850 -775);
FORCEPROP 2 LAST CDS_LIB standard
J 0
(-11175 -650);
DISPLAY INVISIBLE (-11175 -650);
FORCEADD Q_RES..1
(-10325 -50);
FORCEPROP 1 LAST MATERIAL CHIP
J 0
(-10225 0);
DISPLAY 0.510638 (-10225 0);
PAINT SKYBLUE (-10225 0);
FORCEPROP 1 LAST VALUE 33.2
J 0
(-10225 -50);
DISPLAY 0.510638 (-10225 -50);
PAINT SKYBLUE (-10225 -50);
FORCEPROP 2 LAST SEC_TYPE 0402LF
J 0
(-10375 150);
DISPLAY 0.680851 (-10375 150);
DISPLAY INVISIBLE (-10375 150);
FORCEPROP 1 LAST PACK_TYPE 0402LF
J 0
(-10075 -200);
DISPLAY 0.510638 (-10075 -200);
PAINT SKYBLUE (-10075 -200);
DISPLAY INVISIBLE (-10075 -200);
FORCEPROP 1 LAST TOLERANCE 1%
J 0
(-10200 -50);
DISPLAY 0.510638 (-10200 -50);
PAINT SKYBLUE (-10200 -50);
DISPLAY INVISIBLE (-10200 -50);
FORCEPROP 1 LAST PART_NUMBER CS03322FB03
J 0
(-10375 50);
DISPLAY 0.510638 (-10375 50);
PAINT WHITE (-10375 50);
DISPLAY INVISIBLE (-10375 50);
FORCEPROP 1 LAST WATTAGE 1/16W
J 2
(-10350 -200);
DISPLAY 0.510638 (-10350 -200);
PAINT SKYBLUE (-10350 -200);
DISPLAY INVISIBLE (-10350 -200);
FORCEPROP 1 LAST PATH I293
J 0
(-10375 100);
DISPLAY 0.978723 (-10375 100);
PAINT WHITE (-10375 100);
DISPLAY INVISIBLE (-10375 100);
FORCEPROP 2 LAST CDS_LIB pure_quanta
J 0
(-10325 -50);
DISPLAY INVISIBLE (-10325 -50);
FORCEPROP 1 LAST LOCATION R243
J 0
(-10375 -25);
DISPLAY 0.702128 (-10375 -25);
PAINT YELLOW (-10375 -25);
FORCEPROP 1 LASTPIN (-10425 -50) $PN 1
J 0
(-10413 -38);
DISPLAY 0.808511 (-10413 -38);
PAINT WHITE (-10413 -38);
FORCEPROP 1 LASTPIN (-10225 -50) $PN 2
J 0
(-10263 -38);
DISPLAY 0.808511 (-10263 -38);
PAINT WHITE (-10263 -38);
FORCEPROP 2 LAST SEC 1
J 0
(-10375 150);
DISPLAY 0.680851 (-10375 150);
PAINT MONO (-10375 150);
DISPLAY INVISIBLE (-10375 150);
FORCEADD OFFPAGE..1
(-11175 -150);
FORCEPROP 2 LAST $XR0 35 
J 0
(-11396 -150);
DISPLAY 0.638298 (-11396 -150);
PAINT MONO (-11396 -150);
FORCEPROP 2 LAST PATH I294
J 0
(-11125 -75);
DISPLAY 1.021277 (-11125 -75);
DISPLAY INVISIBLE (-11125 -75);
FORCEPROP 1 LAST COMMENT_BODY TRUE
J 0
(-11050 -250);
DISPLAY 0.872340 (-11050 -250);
PAINT PEACH (-11050 -250);
DISPLAY INVISIBLE (-11050 -250);
FORCEPROP 1 LAST OFFPAGE TRUE
J 0
(-10850 -275);
DISPLAY 0.872340 (-10850 -275);
PAINT GREEN (-10850 -275);
DISPLAY INVISIBLE (-10850 -275);
FORCEPROP 2 LAST CDS_LIB standard
J 0
(-11175 -150);
DISPLAY INVISIBLE (-11175 -150);
FORCEADD OFFPAGE..3
(-5925 -550);
FORCEPROP 2 LAST $XR0 15 
J 0
(-5711 -550);
DISPLAY 0.638298 (-5711 -550);
PAINT MONO (-5711 -550);
FORCEPROP 2 LAST PATH I295
J 0
(-5700 -500);
DISPLAY 1.021277 (-5700 -500);
DISPLAY INVISIBLE (-5700 -500);
FORCEPROP 1 LAST COMMENT_BODY TRUE
J 0
(-5975 -650);
DISPLAY 0.872340 (-5975 -650);
PAINT PEACH (-5975 -650);
DISPLAY INVISIBLE (-5975 -650);
FORCEPROP 1 LAST OFFPAGE TRUE
J 0
(-5600 -675);
DISPLAY 0.872340 (-5600 -675);
PAINT GREEN (-5600 -675);
DISPLAY INVISIBLE (-5600 -675);
FORCEPROP 2 LAST CDS_LIB standard
J 0
(-5925 -550);
DISPLAY INVISIBLE (-5925 -550);
FORCEADD OFFPAGE..3
(-5925 -500);
FORCEPROP 2 LAST $XR0 15 
J 0
(-5711 -500);
DISPLAY 0.638298 (-5711 -500);
PAINT MONO (-5711 -500);
FORCEPROP 2 LAST PATH I296
J 0
(-5700 -450);
DISPLAY 1.021277 (-5700 -450);
DISPLAY INVISIBLE (-5700 -450);
FORCEPROP 1 LAST COMMENT_BODY TRUE
J 0
(-5975 -600);
DISPLAY 0.872340 (-5975 -600);
PAINT PEACH (-5975 -600);
DISPLAY INVISIBLE (-5975 -600);
FORCEPROP 1 LAST OFFPAGE TRUE
J 0
(-5600 -625);
DISPLAY 0.872340 (-5600 -625);
PAINT GREEN (-5600 -625);
DISPLAY INVISIBLE (-5600 -625);
FORCEPROP 2 LAST CDS_LIB standard
J 0
(-5925 -500);
DISPLAY INVISIBLE (-5925 -500);
FORCEADD OFFPAGE..5
(-11175 -400);
FORCEPROP 2 LAST $XR3 34 
J 0
(-11699 -400);
DISPLAY 0.638298 (-11699 -400);
PAINT MONO (-11699 -400);
FORCEPROP 2 LAST $XR4 46 
J 0
(-11789 -400);
DISPLAY 0.638298 (-11789 -400);
PAINT MONO (-11789 -400);
FORCEPROP 2 LAST $XR1 12 
J 0
(-11519 -400);
DISPLAY 0.638298 (-11519 -400);
PAINT MONO (-11519 -400);
FORCEPROP 2 LAST $XR0 11 
J 0
(-11429 -400);
DISPLAY 0.638298 (-11429 -400);
PAINT MONO (-11429 -400);
FORCEPROP 2 LAST $XR2 28 
J 0
(-11609 -400);
DISPLAY 0.638298 (-11609 -400);
PAINT MONO (-11609 -400);
FORCEPROP 2 LAST PATH I297
J 0
(-11600 -350);
DISPLAY 1.021277 (-11600 -350);
DISPLAY INVISIBLE (-11600 -350);
FORCEPROP 1 LAST COMMENT_BODY TRUE
J 0
(-11075 -475);
DISPLAY 0.872340 (-11075 -475);
PAINT PEACH (-11075 -475);
DISPLAY INVISIBLE (-11075 -475);
FORCEPROP 1 LAST OFFPAGE TRUE
J 0
(-10850 -525);
DISPLAY 0.872340 (-10850 -525);
PAINT GREEN (-10850 -525);
DISPLAY INVISIBLE (-10850 -525);
FORCEPROP 2 LAST CDS_LIB standard
J 0
(-11175 -400);
DISPLAY INVISIBLE (-11175 -400);
FORCEADD OFFPAGE..2
(-5925 2400);
FORCEPROP 2 LAST $XR0 44 
J 0
(-5736 2400);
DISPLAY 0.638298 (-5736 2400);
PAINT MONO (-5736 2400);
FORCEPROP 2 LAST PATH I301
J 0
(-5750 2475);
DISPLAY 1.021277 (-5750 2475);
DISPLAY INVISIBLE (-5750 2475);
FORCEPROP 1 LAST COMMENT_BODY TRUE
J 0
(-5970 2305);
DISPLAY 0.872340 (-5970 2305);
PAINT PEACH (-5970 2305);
DISPLAY INVISIBLE (-5970 2305);
FORCEPROP 1 LAST OFFPAGE TRUE
J 0
(-5600 2275);
DISPLAY 0.872340 (-5600 2275);
PAINT GREEN (-5600 2275);
DISPLAY INVISIBLE (-5600 2275);
FORCEPROP 2 LAST CDS_LIB standard
J 0
(-5925 2400);
DISPLAY INVISIBLE (-5925 2400);
FORCEADD OFFPAGE..2
(-5925 1800);
FORCEPROP 2 LAST $XR2 27 
J 0
(-5556 1800);
DISPLAY 0.638298 (-5556 1800);
PAINT MONO (-5556 1800);
FORCEPROP 2 LAST $XR0 11 
J 0
(-5736 1800);
DISPLAY 0.638298 (-5736 1800);
PAINT MONO (-5736 1800);
FORCEPROP 2 LAST $XR1 17 
J 0
(-5646 1800);
DISPLAY 0.638298 (-5646 1800);
PAINT MONO (-5646 1800);
FORCEPROP 2 LAST PATH I408
J 0
(-5750 1875);
DISPLAY 1.021277 (-5750 1875);
DISPLAY INVISIBLE (-5750 1875);
FORCEPROP 1 LAST COMMENT_BODY TRUE
J 0
(-5970 1705);
DISPLAY 0.872340 (-5970 1705);
PAINT PEACH (-5970 1705);
DISPLAY INVISIBLE (-5970 1705);
FORCEPROP 1 LAST OFFPAGE TRUE
J 0
(-5600 1675);
DISPLAY 0.872340 (-5600 1675);
PAINT GREEN (-5600 1675);
DISPLAY INVISIBLE (-5600 1675);
FORCEPROP 2 LAST CDS_LIB standard
J 0
(-5925 1800);
DISPLAY INVISIBLE (-5925 1800);
FORCEADD OFFPAGE..5
(-11175 -700);
FORCEPROP 2 LAST $XR0 10 
J 0
(-11429 -700);
DISPLAY 0.638298 (-11429 -700);
PAINT MONO (-11429 -700);
FORCEPROP 2 LAST PATH I416
J 0
(-11125 -625);
DISPLAY 1.021277 (-11125 -625);
DISPLAY INVISIBLE (-11125 -625);
FORCEPROP 1 LAST COMMENT_BODY TRUE
J 0
(-11075 -775);
DISPLAY 0.872340 (-11075 -775);
PAINT PEACH (-11075 -775);
DISPLAY INVISIBLE (-11075 -775);
FORCEPROP 1 LAST OFFPAGE TRUE
J 0
(-10850 -825);
DISPLAY 0.872340 (-10850 -825);
PAINT GREEN (-10850 -825);
DISPLAY INVISIBLE (-10850 -825);
FORCEPROP 2 LAST CDS_LIB standard
J 0
(-11175 -700);
DISPLAY INVISIBLE (-11175 -700);
FORCEADD OFFPAGE..5
R 2
(-5925 850);
FORCEPROP 2 LAST $XR0 15 
J 0
(-5736 850);
DISPLAY 0.638298 (-5736 850);
PAINT MONO (-5736 850);
FORCEPROP 2 LAST PATH I424
J 2
(-5675 900);
DISPLAY 1.021277 (-5675 900);
DISPLAY INVISIBLE (-5675 900);
FORCEPROP 1 LAST COMMENT_BODY TRUE
J 2
(-6025 775);
DISPLAY 0.872340 (-6025 775);
PAINT PEACH (-6025 775);
DISPLAY INVISIBLE (-6025 775);
FORCEPROP 1 LAST OFFPAGE TRUE
J 2
(-6250 725);
DISPLAY 0.872340 (-6250 725);
PAINT GREEN (-6250 725);
DISPLAY INVISIBLE (-6250 725);
FORCEPROP 2 LAST CDS_LIB standard
J 2
(-5925 850);
DISPLAY INVISIBLE (-5925 850);
FORCEADD OFFPAGE..6
R 2
(-5925 900);
FORCEPROP 2 LAST $XR0 15 
J 0
(-5711 900);
DISPLAY 0.638298 (-5711 900);
PAINT MONO (-5711 900);
FORCEPROP 2 LAST PATH I425
J 2
(-5700 950);
DISPLAY 1.021277 (-5700 950);
DISPLAY INVISIBLE (-5700 950);
FORCEPROP 1 LAST COMMENT_BODY TRUE
J 2
(-6025 825);
DISPLAY 0.872340 (-6025 825);
PAINT PEACH (-6025 825);
DISPLAY INVISIBLE (-6025 825);
FORCEPROP 1 LAST OFFPAGE TRUE
J 2
(-6250 775);
DISPLAY 0.872340 (-6250 775);
PAINT GREEN (-6250 775);
DISPLAY INVISIBLE (-6250 775);
FORCEPROP 2 LAST CDS_LIB standard
J 2
(-5925 900);
DISPLAY INVISIBLE (-5925 900);
FORCEADD OFFPAGE..6
(-11175 2150);
FORCEPROP 2 LAST $XR0 12 
J 0
(-11424 2150);
DISPLAY 0.638298 (-11424 2150);
PAINT MONO (-11424 2150);
FORCEPROP 2 LAST $XR1 27 
J 0
(-11514 2150);
DISPLAY 0.638298 (-11514 2150);
PAINT MONO (-11514 2150);
FORCEPROP 2 LAST PATH I426
J 0
(-11400 2200);
DISPLAY 1.021277 (-11400 2200);
DISPLAY INVISIBLE (-11400 2200);
FORCEPROP 1 LAST COMMENT_BODY TRUE
J 0
(-11075 2075);
DISPLAY 0.872340 (-11075 2075);
PAINT PEACH (-11075 2075);
DISPLAY INVISIBLE (-11075 2075);
FORCEPROP 1 LAST OFFPAGE TRUE
J 0
(-10850 2025);
DISPLAY 0.872340 (-10850 2025);
PAINT GREEN (-10850 2025);
DISPLAY INVISIBLE (-10850 2025);
FORCEPROP 2 LAST CDS_LIB standard
J 0
(-11175 2150);
DISPLAY INVISIBLE (-11175 2150);
FORCEADD OFFPAGE..1
(-11175 2200);
FORCEPROP 2 LAST $XR1 27 
J 0
(-11516 2200);
DISPLAY 0.638298 (-11516 2200);
PAINT MONO (-11516 2200);
FORCEPROP 2 LAST $XR0 12 
J 0
(-11426 2200);
DISPLAY 0.638298 (-11426 2200);
PAINT MONO (-11426 2200);
FORCEPROP 2 LAST PATH I427
J 0
(-11425 2250);
DISPLAY 1.021277 (-11425 2250);
DISPLAY INVISIBLE (-11425 2250);
FORCEPROP 1 LAST COMMENT_BODY TRUE
J 0
(-11050 2100);
DISPLAY 0.872340 (-11050 2100);
PAINT PEACH (-11050 2100);
DISPLAY INVISIBLE (-11050 2100);
FORCEPROP 1 LAST OFFPAGE TRUE
J 0
(-10850 2075);
DISPLAY 0.872340 (-10850 2075);
PAINT GREEN (-10850 2075);
DISPLAY INVISIBLE (-10850 2075);
FORCEPROP 2 LAST CDS_LIB standard
J 0
(-11175 2200);
DISPLAY INVISIBLE (-11175 2200);
FORCEADD OFFPAGE..1
(-11175 1950);
FORCEPROP 2 LAST $XR0 12 
J 0
(-11426 1950);
DISPLAY 0.638298 (-11426 1950);
PAINT MONO (-11426 1950);
FORCEPROP 2 LAST $XR1 26 
J 0
(-11516 1950);
DISPLAY 0.638298 (-11516 1950);
PAINT MONO (-11516 1950);
FORCEPROP 2 LAST $XR2 27 
J 0
(-11606 1950);
DISPLAY 0.638298 (-11606 1950);
PAINT MONO (-11606 1950);
FORCEPROP 2 LAST PATH I430
J 0
(-11425 2000);
DISPLAY 1.021277 (-11425 2000);
DISPLAY INVISIBLE (-11425 2000);
FORCEPROP 1 LAST COMMENT_BODY TRUE
J 0
(-11050 1850);
DISPLAY 0.872340 (-11050 1850);
PAINT PEACH (-11050 1850);
DISPLAY INVISIBLE (-11050 1850);
FORCEPROP 1 LAST OFFPAGE TRUE
J 0
(-10850 1825);
DISPLAY 0.872340 (-10850 1825);
PAINT GREEN (-10850 1825);
DISPLAY INVISIBLE (-10850 1825);
FORCEPROP 2 LAST CDS_LIB standard
J 0
(-11175 1950);
DISPLAY INVISIBLE (-11175 1950);
FORCEADD OFFPAGE..6
(-11175 1900);
FORCEPROP 2 LAST $XR0 12 
J 0
(-11424 1900);
DISPLAY 0.638298 (-11424 1900);
PAINT MONO (-11424 1900);
FORCEPROP 2 LAST $XR1 27 
J 0
(-11514 1900);
DISPLAY 0.638298 (-11514 1900);
PAINT MONO (-11514 1900);
FORCEPROP 2 LAST PATH I432
J 0
(-11400 1950);
DISPLAY 1.021277 (-11400 1950);
DISPLAY INVISIBLE (-11400 1950);
FORCEPROP 1 LAST COMMENT_BODY TRUE
J 0
(-11075 1825);
DISPLAY 0.872340 (-11075 1825);
PAINT PEACH (-11075 1825);
DISPLAY INVISIBLE (-11075 1825);
FORCEPROP 1 LAST OFFPAGE TRUE
J 0
(-10850 1775);
DISPLAY 0.872340 (-10850 1775);
PAINT GREEN (-10850 1775);
DISPLAY INVISIBLE (-10850 1775);
FORCEPROP 2 LAST CDS_LIB standard
J 0
(-11175 1900);
DISPLAY INVISIBLE (-11175 1900);
FORCEADD OFFPAGE..1
(-11175 1850);
FORCEPROP 2 LAST $XR0 12 
J 0
(-11426 1850);
DISPLAY 0.638298 (-11426 1850);
PAINT MONO (-11426 1850);
FORCEPROP 2 LAST $XR1 27 
J 0
(-11516 1850);
DISPLAY 0.638298 (-11516 1850);
PAINT MONO (-11516 1850);
FORCEPROP 2 LAST PATH I433
J 0
(-11425 1900);
DISPLAY 1.021277 (-11425 1900);
DISPLAY INVISIBLE (-11425 1900);
FORCEPROP 1 LAST COMMENT_BODY TRUE
J 0
(-11050 1750);
DISPLAY 0.872340 (-11050 1750);
PAINT PEACH (-11050 1750);
DISPLAY INVISIBLE (-11050 1750);
FORCEPROP 1 LAST OFFPAGE TRUE
J 0
(-10850 1725);
DISPLAY 0.872340 (-10850 1725);
PAINT GREEN (-10850 1725);
DISPLAY INVISIBLE (-10850 1725);
FORCEPROP 2 LAST CDS_LIB standard
J 0
(-11175 1850);
DISPLAY INVISIBLE (-11175 1850);
FORCEADD OFFPAGE..6
(-11175 1750);
FORCEPROP 2 LAST $XR0 12 
J 0
(-11424 1750);
DISPLAY 0.638298 (-11424 1750);
PAINT MONO (-11424 1750);
FORCEPROP 2 LAST $XR1 27 
J 0
(-11514 1750);
DISPLAY 0.638298 (-11514 1750);
PAINT MONO (-11514 1750);
FORCEPROP 2 LAST PATH I434
J 0
(-11400 1800);
DISPLAY 1.021277 (-11400 1800);
DISPLAY INVISIBLE (-11400 1800);
FORCEPROP 1 LAST COMMENT_BODY TRUE
J 0
(-11075 1675);
DISPLAY 0.872340 (-11075 1675);
PAINT PEACH (-11075 1675);
DISPLAY INVISIBLE (-11075 1675);
FORCEPROP 1 LAST OFFPAGE TRUE
J 0
(-10850 1625);
DISPLAY 0.872340 (-10850 1625);
PAINT GREEN (-10850 1625);
DISPLAY INVISIBLE (-10850 1625);
FORCEPROP 2 LAST CDS_LIB standard
J 0
(-11175 1750);
DISPLAY INVISIBLE (-11175 1750);
FORCEADD OFFPAGE..1
(-11175 1800);
FORCEPROP 2 LAST $XR1 27 
J 0
(-11486 1800);
DISPLAY 0.638298 (-11486 1800);
PAINT MONO (-11486 1800);
FORCEPROP 2 LAST $XR0 12 
J 0
(-11396 1800);
DISPLAY 0.638298 (-11396 1800);
PAINT MONO (-11396 1800);
FORCEPROP 2 LAST PATH I435
J 0
(-11425 1850);
DISPLAY 1.021277 (-11425 1850);
DISPLAY INVISIBLE (-11425 1850);
FORCEPROP 1 LAST COMMENT_BODY TRUE
J 0
(-11050 1700);
DISPLAY 0.872340 (-11050 1700);
PAINT PEACH (-11050 1700);
DISPLAY INVISIBLE (-11050 1700);
FORCEPROP 1 LAST OFFPAGE TRUE
J 0
(-10850 1675);
DISPLAY 0.872340 (-10850 1675);
PAINT GREEN (-10850 1675);
DISPLAY INVISIBLE (-10850 1675);
FORCEPROP 2 LAST CDS_LIB standard
J 0
(-11175 1800);
DISPLAY INVISIBLE (-11175 1800);
FORCEADD OFFPAGE..1
(-11175 -500);
FORCEPROP 2 LAST $XR0 11 
J 0
(-11426 -500);
DISPLAY 0.638298 (-11426 -500);
PAINT MONO (-11426 -500);
FORCEPROP 2 LAST $XR1 13 
J 0
(-11516 -500);
DISPLAY 0.638298 (-11516 -500);
PAINT MONO (-11516 -500);
FORCEPROP 2 LAST $XR2 35 
J 0
(-11606 -500);
DISPLAY 0.638298 (-11606 -500);
PAINT MONO (-11606 -500);
FORCEPROP 2 LAST $XR3 36 
J 0
(-11696 -500);
DISPLAY 0.638298 (-11696 -500);
PAINT MONO (-11696 -500);
FORCEPROP 2 LAST PATH I443
J 0
(-11125 -425);
DISPLAY 1.021277 (-11125 -425);
DISPLAY INVISIBLE (-11125 -425);
FORCEPROP 1 LAST COMMENT_BODY TRUE
J 0
(-11050 -600);
DISPLAY 0.872340 (-11050 -600);
PAINT PEACH (-11050 -600);
DISPLAY INVISIBLE (-11050 -600);
FORCEPROP 1 LAST OFFPAGE TRUE
J 0
(-10850 -625);
DISPLAY 0.872340 (-10850 -625);
PAINT GREEN (-10850 -625);
DISPLAY INVISIBLE (-10850 -625);
FORCEPROP 2 LAST CDS_LIB standard
J 0
(-11175 -500);
DISPLAY INVISIBLE (-11175 -500);
FORCEADD UNIVERSAL_POWER..1
(-10225 3725);
FORCEPROP 3 LASTPIN (-10225 3675) SIG_NAME P12V_AUX\g
J 0
(-10215 3685);
DISPLAY 0.659574 (-10215 3685);
PAINT MONO (-10215 3685);
DISPLAY INVISIBLE (-10215 3685);
FORCEPROP 1 LAST HDL_POWER P12V_AUX
J 1
(-10225 3775);
DISPLAY 0.702128 (-10225 3775);
PAINT GREEN (-10225 3775);
FORCEPROP 1 LAST PATH I446
J 0
(-10175 3750);
DISPLAY 0.872340 (-10175 3750);
PAINT AQUA (-10175 3750);
DISPLAY INVISIBLE (-10175 3750);
FORCEPROP 2 LAST CDS_LIB logical_power
J 0
(-10225 3725);
DISPLAY INVISIBLE (-10225 3725);
FORCEADD UNIVERSAL_GND..1
(-10225 3000);
FORCEPROP 3 LASTPIN (-10225 3050) SIG_NAME GND\g
J 0
(-10215 3060);
DISPLAY 0.659574 (-10215 3060);
PAINT MONO (-10215 3060);
DISPLAY INVISIBLE (-10215 3060);
FORCEPROP 1 LAST PATH I447
J 0
(-10150 3000);
DISPLAY 0.872340 (-10150 3000);
PAINT AQUA (-10150 3000);
DISPLAY INVISIBLE (-10150 3000);
FORCEPROP 1 LAST HDL_POWER GND
J 1
(-10200 2925);
DISPLAY 0.702128 (-10200 2925);
PAINT GREEN (-10200 2925);
DISPLAY INVISIBLE (-10200 2925);
FORCEPROP 2 LAST CDS_LIB logical_power
J 0
(-10225 3000);
DISPLAY INVISIBLE (-10225 3000);
FORCEADD Q_RES..1
R 2
(-6425 2850);
FORCEPROP 1 LAST MATERIAL CHIP
J 0
(-6200 2850);
DISPLAY 0.510638 (-6200 2850);
PAINT SKYBLUE (-6200 2850);
FORCEPROP 1 LAST VALUE 0
J 2
(-6275 2850);
DISPLAY 0.510638 (-6275 2850);
PAINT SKYBLUE (-6275 2850);
FORCEPROP 2 LAST CDS_LIB pure_quanta
J 2
(-6425 2944);
DISPLAY INVISIBLE (-6425 2944);
FORCEPROP 1 LAST PATH I456
J 2
(-6375 3000);
DISPLAY 0.978723 (-6375 3000);
PAINT WHITE (-6375 3000);
DISPLAY INVISIBLE (-6375 3000);
FORCEPROP 1 LAST PART_NUMBER CS00002JB13
J 2
(-6475 2800);
DISPLAY 0.510638 (-6475 2800);
PAINT WHITE (-6475 2800);
DISPLAY INVISIBLE (-6475 2800);
FORCEPROP 1 LAST TOLERANCE 5%
J 2
(-6725 2825);
DISPLAY 0.510638 (-6725 2825);
PAINT SKYBLUE (-6725 2825);
DISPLAY INVISIBLE (-6725 2825);
FORCEPROP 1 LAST WATTAGE 1/16W
J 0
(-6950 2825);
DISPLAY 0.510638 (-6950 2825);
PAINT SKYBLUE (-6950 2825);
DISPLAY INVISIBLE (-6950 2825);
FORCEPROP 1 LAST PACK_TYPE 0402LF
J 2
(-6525 2825);
DISPLAY 0.510638 (-6525 2825);
PAINT SKYBLUE (-6525 2825);
DISPLAY INVISIBLE (-6525 2825);
FORCEPROP 1 LAST LOCATION R822
J 2
(-6500 2850);
DISPLAY 0.702128 (-6500 2850);
PAINT YELLOW (-6500 2850);
FORCEPROP 0 LAST $SEC 1
J 0
(-6325 2925);
DISPLAY 0.680851 (-6325 2925);
PAINT MONO (-6325 2925);
DISPLAY INVISIBLE (-6325 2925);
FORCEPROP 0 LAST CDS_SEC 1
J 0
(-6325 2925);
DISPLAY 1.021277 (-6325 2925);
DISPLAY INVISIBLE (-6325 2925);
FORCEPROP 1 LASTPIN (-6325 2850) $PN 1
R 2
J 0
(-6337 2936);
DISPLAY 0.808511 (-6337 2936);
PAINT WHITE (-6337 2936);
DISPLAY INVISIBLE (-6337 2936);
FORCEPROP 1 LASTPIN (-6525 2850) $PN 2
R 2
J 0
(-6487 2936);
DISPLAY 0.808511 (-6487 2936);
PAINT WHITE (-6487 2936);
DISPLAY INVISIBLE (-6487 2936);
FORCEADD OFFPAGE..1
R 2
(-5425 2850);
FORCEPROP 2 LAST $XR0 10 
J 0
(-5239 2850);
DISPLAY 0.638298 (-5239 2850);
PAINT MONO (-5239 2850);
FORCEPROP 2 LAST PATH I457
J 0
(-5250 2925);
DISPLAY 1.021277 (-5250 2925);
DISPLAY INVISIBLE (-5250 2925);
FORCEPROP 1 LAST COMMENT_BODY TRUE
J 2
(-5550 2750);
DISPLAY 0.872340 (-5550 2750);
PAINT PEACH (-5550 2750);
DISPLAY INVISIBLE (-5550 2750);
FORCEPROP 1 LAST OFFPAGE TRUE
J 2
(-5750 2725);
DISPLAY 0.872340 (-5750 2725);
PAINT GREEN (-5750 2725);
DISPLAY INVISIBLE (-5750 2725);
FORCEPROP 2 LAST CDS_LIB standard
J 0
(-5425 2850);
DISPLAY INVISIBLE (-5425 2850);
FORCEADD Q_RES..1
(-10350 2200);
FORCEPROP 1 LAST MATERIAL CHIP
J 2
(-10050 2200);
DISPLAY 0.510638 (-10050 2200);
PAINT SKYBLUE (-10050 2200);
FORCEPROP 1 LAST VALUE 33.2
J 0
(-10250 2200);
DISPLAY 0.510638 (-10250 2200);
PAINT SKYBLUE (-10250 2200);
FORCEPROP 2 LAST SEC_TYPE 0402LF
J 0
(-10400 2400);
DISPLAY 0.680851 (-10400 2400);
DISPLAY INVISIBLE (-10400 2400);
FORCEPROP 2 LAST CDS_LIB pure_quanta
J 0
(-10350 2200);
DISPLAY INVISIBLE (-10350 2200);
FORCEPROP 1 LAST PATH I458
J 0
(-10400 2350);
DISPLAY 0.978723 (-10400 2350);
PAINT WHITE (-10400 2350);
DISPLAY INVISIBLE (-10400 2350);
FORCEPROP 1 LAST WATTAGE 1/16W
J 2
(-10375 2050);
DISPLAY 0.510638 (-10375 2050);
PAINT SKYBLUE (-10375 2050);
DISPLAY INVISIBLE (-10375 2050);
FORCEPROP 1 LAST PACK_TYPE 0402LF
J 0
(-10100 2050);
DISPLAY 0.510638 (-10100 2050);
PAINT SKYBLUE (-10100 2050);
DISPLAY INVISIBLE (-10100 2050);
FORCEPROP 1 LAST PART_NUMBER CS03322FB03
J 0
(-10400 2300);
DISPLAY 0.510638 (-10400 2300);
PAINT WHITE (-10400 2300);
DISPLAY INVISIBLE (-10400 2300);
FORCEPROP 1 LAST TOLERANCE 1%
J 0
(-10225 2200);
DISPLAY 0.510638 (-10225 2200);
PAINT SKYBLUE (-10225 2200);
DISPLAY INVISIBLE (-10225 2200);
FORCEPROP 1 LAST LOCATION R36
J 2
(-10425 2200);
DISPLAY 0.702128 (-10425 2200);
PAINT YELLOW (-10425 2200);
FORCEPROP 1 LASTPIN (-10450 2200) $PN 1
J 0
(-10438 2212);
DISPLAY 0.808511 (-10438 2212);
PAINT WHITE (-10438 2212);
FORCEPROP 1 LASTPIN (-10250 2200) $PN 2
J 0
(-10288 2212);
DISPLAY 0.808511 (-10288 2212);
PAINT WHITE (-10288 2212);
FORCEPROP 0 LAST SEC 1
J 0
(-10600 2250);
DISPLAY 0.680851 (-10600 2250);
PAINT MONO (-10600 2250);
DISPLAY INVISIBLE (-10600 2250);
FORCEADD Q_RES..1
(-10350 2150);
FORCEPROP 1 LAST VALUE 33.2
J 0
(-10250 2150);
DISPLAY 0.510638 (-10250 2150);
PAINT SKYBLUE (-10250 2150);
FORCEPROP 1 LAST MATERIAL CHIP
J 2
(-10050 2150);
DISPLAY 0.510638 (-10050 2150);
PAINT SKYBLUE (-10050 2150);
FORCEPROP 2 LAST SEC_TYPE 0402LF
J 0
(-10400 2350);
DISPLAY 0.680851 (-10400 2350);
DISPLAY INVISIBLE (-10400 2350);
FORCEPROP 2 LAST CDS_LIB pure_quanta
J 0
(-10350 2150);
DISPLAY INVISIBLE (-10350 2150);
FORCEPROP 1 LAST PATH I459
J 0
(-10400 2300);
DISPLAY 0.978723 (-10400 2300);
PAINT WHITE (-10400 2300);
DISPLAY INVISIBLE (-10400 2300);
FORCEPROP 1 LAST WATTAGE 1/16W
J 2
(-10375 2000);
DISPLAY 0.510638 (-10375 2000);
PAINT SKYBLUE (-10375 2000);
DISPLAY INVISIBLE (-10375 2000);
FORCEPROP 1 LAST PACK_TYPE 0402LF
J 0
(-10100 2000);
DISPLAY 0.510638 (-10100 2000);
PAINT SKYBLUE (-10100 2000);
DISPLAY INVISIBLE (-10100 2000);
FORCEPROP 1 LAST PART_NUMBER CS03322FB03
J 0
(-10400 2250);
DISPLAY 0.510638 (-10400 2250);
PAINT WHITE (-10400 2250);
DISPLAY INVISIBLE (-10400 2250);
FORCEPROP 1 LAST TOLERANCE 1%
J 0
(-10225 2150);
DISPLAY 0.510638 (-10225 2150);
PAINT SKYBLUE (-10225 2150);
DISPLAY INVISIBLE (-10225 2150);
FORCEPROP 1 LAST LOCATION R46
J 2
(-10425 2150);
DISPLAY 0.702128 (-10425 2150);
PAINT YELLOW (-10425 2150);
FORCEPROP 1 LASTPIN (-10450 2150) $PN 1
J 0
(-10438 2162);
DISPLAY 0.808511 (-10438 2162);
PAINT WHITE (-10438 2162);
FORCEPROP 1 LASTPIN (-10250 2150) $PN 2
J 0
(-10288 2162);
DISPLAY 0.808511 (-10288 2162);
PAINT WHITE (-10288 2162);
FORCEPROP 0 LAST SEC 1
J 0
(-10600 2200);
DISPLAY 0.680851 (-10600 2200);
PAINT MONO (-10600 2200);
DISPLAY INVISIBLE (-10600 2200);
FORCEADD OFFPAGE..2
(-4500 150);
FORCEPROP 2 LAST $XR0 15 
J 0
(-4311 150);
DISPLAY 0.638298 (-4311 150);
PAINT MONO (-4311 150);
FORCEPROP 2 LAST $XR1 50 
J 0
(-4221 150);
DISPLAY 0.638298 (-4221 150);
PAINT MONO (-4221 150);
FORCEPROP 2 LAST PATH I469
J 0
(-4125 200);
DISPLAY 0.680851 (-4125 200);
DISPLAY INVISIBLE (-4125 200);
FORCEPROP 1 LAST COMMENT_BODY TRUE
J 0
(-4545 55);
DISPLAY 0.872340 (-4545 55);
PAINT PEACH (-4545 55);
DISPLAY INVISIBLE (-4545 55);
FORCEPROP 1 LAST OFFPAGE TRUE
J 0
(-4175 25);
DISPLAY 0.872340 (-4175 25);
PAINT GREEN (-4175 25);
DISPLAY INVISIBLE (-4175 25);
FORCEPROP 2 LAST CDS_LIB standard
J 0
(-4500 150);
DISPLAY INVISIBLE (-4500 150);
FORCEADD OFFPAGE..6
(-11175 2400);
FORCEPROP 2 LAST $XR0 14 
J 0
(-11424 2400);
DISPLAY 0.638298 (-11424 2400);
PAINT MONO (-11424 2400);
FORCEPROP 2 LAST PATH I470
J 0
(-11450 2450);
DISPLAY 0.680851 (-11450 2450);
DISPLAY INVISIBLE (-11450 2450);
FORCEPROP 1 LAST COMMENT_BODY TRUE
J 0
(-11075 2325);
DISPLAY 0.872340 (-11075 2325);
PAINT PEACH (-11075 2325);
DISPLAY INVISIBLE (-11075 2325);
FORCEPROP 1 LAST OFFPAGE TRUE
J 0
(-10850 2275);
DISPLAY 0.872340 (-10850 2275);
PAINT GREEN (-10850 2275);
DISPLAY INVISIBLE (-10850 2275);
FORCEPROP 2 LAST CDS_LIB standard
J 0
(-11175 2400);
DISPLAY INVISIBLE (-11175 2400);
FORCEADD OFFPAGE..1
(-11175 2450);
FORCEPROP 2 LAST $XR0 14 
J 0
(-11426 2450);
DISPLAY 0.638298 (-11426 2450);
PAINT MONO (-11426 2450);
FORCEPROP 2 LAST PATH I471
J 0
(-11425 2500);
DISPLAY 0.680851 (-11425 2500);
DISPLAY INVISIBLE (-11425 2500);
FORCEPROP 1 LAST COMMENT_BODY TRUE
J 0
(-11050 2350);
DISPLAY 0.872340 (-11050 2350);
PAINT PEACH (-11050 2350);
DISPLAY INVISIBLE (-11050 2350);
FORCEPROP 1 LAST OFFPAGE TRUE
J 0
(-10850 2325);
DISPLAY 0.872340 (-10850 2325);
PAINT GREEN (-10850 2325);
DISPLAY INVISIBLE (-10850 2325);
FORCEPROP 2 LAST CDS_LIB standard
J 0
(-11175 2450);
DISPLAY INVISIBLE (-11175 2450);
FORCEADD OFFPAGE..6
(-11175 2500);
FORCEPROP 2 LAST $XR0 14 
J 0
(-11424 2500);
DISPLAY 0.638298 (-11424 2500);
PAINT MONO (-11424 2500);
FORCEPROP 2 LAST PATH I472
J 0
(-11450 2550);
DISPLAY 0.680851 (-11450 2550);
DISPLAY INVISIBLE (-11450 2550);
FORCEPROP 1 LAST COMMENT_BODY TRUE
J 0
(-11075 2425);
DISPLAY 0.872340 (-11075 2425);
PAINT PEACH (-11075 2425);
DISPLAY INVISIBLE (-11075 2425);
FORCEPROP 1 LAST OFFPAGE TRUE
J 0
(-10850 2375);
DISPLAY 0.872340 (-10850 2375);
PAINT GREEN (-10850 2375);
DISPLAY INVISIBLE (-10850 2375);
FORCEPROP 2 LAST CDS_LIB standard
J 0
(-11175 2500);
DISPLAY INVISIBLE (-11175 2500);
FORCEADD OFFPAGE..1
(-11175 2550);
FORCEPROP 2 LAST $XR0 14 
J 0
(-11426 2550);
DISPLAY 0.638298 (-11426 2550);
PAINT MONO (-11426 2550);
FORCEPROP 2 LAST PATH I473
J 0
(-11425 2600);
DISPLAY 0.680851 (-11425 2600);
DISPLAY INVISIBLE (-11425 2600);
FORCEPROP 1 LAST COMMENT_BODY TRUE
J 0
(-11050 2450);
DISPLAY 0.872340 (-11050 2450);
PAINT PEACH (-11050 2450);
DISPLAY INVISIBLE (-11050 2450);
FORCEPROP 1 LAST OFFPAGE TRUE
J 0
(-10850 2425);
DISPLAY 0.872340 (-10850 2425);
PAINT GREEN (-10850 2425);
DISPLAY INVISIBLE (-10850 2425);
FORCEPROP 2 LAST CDS_LIB standard
J 0
(-11175 2550);
DISPLAY INVISIBLE (-11175 2550);
FORCEADD OFFPAGE..6
(-11175 2600);
FORCEPROP 2 LAST $XR0 14 
J 0
(-11424 2600);
DISPLAY 0.638298 (-11424 2600);
PAINT MONO (-11424 2600);
FORCEPROP 2 LAST PATH I474
J 0
(-11450 2650);
DISPLAY 0.680851 (-11450 2650);
DISPLAY INVISIBLE (-11450 2650);
FORCEPROP 1 LAST COMMENT_BODY TRUE
J 0
(-11075 2525);
DISPLAY 0.872340 (-11075 2525);
PAINT PEACH (-11075 2525);
DISPLAY INVISIBLE (-11075 2525);
FORCEPROP 1 LAST OFFPAGE TRUE
J 0
(-10850 2475);
DISPLAY 0.872340 (-10850 2475);
PAINT GREEN (-10850 2475);
DISPLAY INVISIBLE (-10850 2475);
FORCEPROP 2 LAST CDS_LIB standard
J 0
(-11175 2600);
DISPLAY INVISIBLE (-11175 2600);
FORCEADD OFFPAGE..1
(-11175 2650);
FORCEPROP 2 LAST $XR0 14 
J 0
(-11426 2650);
DISPLAY 0.638298 (-11426 2650);
PAINT MONO (-11426 2650);
FORCEPROP 2 LAST PATH I475
J 0
(-11425 2700);
DISPLAY 0.680851 (-11425 2700);
DISPLAY INVISIBLE (-11425 2700);
FORCEPROP 1 LAST COMMENT_BODY TRUE
J 0
(-11050 2550);
DISPLAY 0.872340 (-11050 2550);
PAINT PEACH (-11050 2550);
DISPLAY INVISIBLE (-11050 2550);
FORCEPROP 1 LAST OFFPAGE TRUE
J 0
(-10850 2525);
DISPLAY 0.872340 (-10850 2525);
PAINT GREEN (-10850 2525);
DISPLAY INVISIBLE (-10850 2525);
FORCEPROP 2 LAST CDS_LIB standard
J 0
(-11175 2650);
DISPLAY INVISIBLE (-11175 2650);
FORCEADD OFFPAGE..6
(-11175 2050);
FORCEPROP 2 LAST $XR1 27 
J 0
(-11514 2050);
DISPLAY 0.638298 (-11514 2050);
PAINT MONO (-11514 2050);
FORCEPROP 2 LAST $XR0 12 
J 0
(-11424 2050);
DISPLAY 0.638298 (-11424 2050);
PAINT MONO (-11424 2050);
FORCEPROP 2 LAST PATH I477
J 0
(-11450 2100);
DISPLAY 0.680851 (-11450 2100);
DISPLAY INVISIBLE (-11450 2100);
FORCEPROP 1 LAST COMMENT_BODY TRUE
J 0
(-11075 1975);
DISPLAY 0.872340 (-11075 1975);
PAINT PEACH (-11075 1975);
DISPLAY INVISIBLE (-11075 1975);
FORCEPROP 1 LAST OFFPAGE TRUE
J 0
(-10850 1925);
DISPLAY 0.872340 (-10850 1925);
PAINT GREEN (-10850 1925);
DISPLAY INVISIBLE (-10850 1925);
FORCEPROP 2 LAST CDS_LIB standard
J 0
(-11175 2050);
DISPLAY INVISIBLE (-11175 2050);
FORCEADD OFFPAGE..1
(-11175 2100);
FORCEPROP 2 LAST $XR1 27 
J 0
(-11576 2100);
DISPLAY 0.638298 (-11576 2100);
PAINT MONO (-11576 2100);
FORCEPROP 2 LAST $XR0 12 
J 0
(-11486 2100);
DISPLAY 0.638298 (-11486 2100);
PAINT MONO (-11486 2100);
FORCEPROP 2 LAST PATH I478
J 0
(-11425 2150);
DISPLAY 0.680851 (-11425 2150);
DISPLAY INVISIBLE (-11425 2150);
FORCEPROP 1 LAST COMMENT_BODY TRUE
J 0
(-11050 2000);
DISPLAY 0.872340 (-11050 2000);
PAINT PEACH (-11050 2000);
DISPLAY INVISIBLE (-11050 2000);
FORCEPROP 1 LAST OFFPAGE TRUE
J 0
(-10850 1975);
DISPLAY 0.872340 (-10850 1975);
PAINT GREEN (-10850 1975);
DISPLAY INVISIBLE (-10850 1975);
FORCEPROP 2 LAST CDS_LIB standard
J 0
(-11175 2100);
DISPLAY INVISIBLE (-11175 2100);
FORCEADD OFFPAGE..1
(-11175 1100);
FORCEPROP 2 LAST $XR1 27 
J 0
(-11486 1100);
DISPLAY 0.638298 (-11486 1100);
PAINT MONO (-11486 1100);
FORCEPROP 2 LAST $XR0 12 
J 0
(-11396 1100);
DISPLAY 0.638298 (-11396 1100);
PAINT MONO (-11396 1100);
FORCEPROP 2 LAST PATH I481
J 0
(-11425 1150);
DISPLAY 0.680851 (-11425 1150);
DISPLAY INVISIBLE (-11425 1150);
FORCEPROP 1 LAST COMMENT_BODY TRUE
J 0
(-11050 1000);
DISPLAY 0.872340 (-11050 1000);
PAINT PEACH (-11050 1000);
DISPLAY INVISIBLE (-11050 1000);
FORCEPROP 1 LAST OFFPAGE TRUE
J 0
(-10850 975);
DISPLAY 0.872340 (-10850 975);
PAINT GREEN (-10850 975);
DISPLAY INVISIBLE (-10850 975);
FORCEPROP 2 LAST CDS_LIB standard
J 0
(-11175 1100);
DISPLAY INVISIBLE (-11175 1100);
FORCEADD OFFPAGE..6
(-11175 1050);
FORCEPROP 2 LAST $XR0 12 
J 0
(-11424 1050);
DISPLAY 0.638298 (-11424 1050);
PAINT MONO (-11424 1050);
FORCEPROP 2 LAST $XR1 27 
J 0
(-11514 1050);
DISPLAY 0.638298 (-11514 1050);
PAINT MONO (-11514 1050);
FORCEPROP 2 LAST PATH I482
J 0
(-11450 1100);
DISPLAY 0.680851 (-11450 1100);
DISPLAY INVISIBLE (-11450 1100);
FORCEPROP 1 LAST COMMENT_BODY TRUE
J 0
(-11075 975);
DISPLAY 0.872340 (-11075 975);
PAINT PEACH (-11075 975);
DISPLAY INVISIBLE (-11075 975);
FORCEPROP 1 LAST OFFPAGE TRUE
J 0
(-10850 925);
DISPLAY 0.872340 (-10850 925);
PAINT GREEN (-10850 925);
DISPLAY INVISIBLE (-10850 925);
FORCEPROP 2 LAST CDS_LIB standard
J 0
(-11175 1050);
DISPLAY INVISIBLE (-11175 1050);
FORCEADD OFFPAGE..1
(-11175 1000);
FORCEPROP 2 LAST $XR0 12 
J 0
(-11426 1000);
DISPLAY 0.638298 (-11426 1000);
PAINT MONO (-11426 1000);
FORCEPROP 2 LAST PATH I483
J 0
(-11425 1050);
DISPLAY 0.680851 (-11425 1050);
DISPLAY INVISIBLE (-11425 1050);
FORCEPROP 1 LAST COMMENT_BODY TRUE
J 0
(-11050 900);
DISPLAY 0.872340 (-11050 900);
PAINT PEACH (-11050 900);
DISPLAY INVISIBLE (-11050 900);
FORCEPROP 1 LAST OFFPAGE TRUE
J 0
(-10850 875);
DISPLAY 0.872340 (-10850 875);
PAINT GREEN (-10850 875);
DISPLAY INVISIBLE (-10850 875);
FORCEPROP 2 LAST CDS_LIB standard
J 0
(-11175 1000);
DISPLAY INVISIBLE (-11175 1000);
FORCEADD OFFPAGE..6
(-11175 950);
FORCEPROP 2 LAST $XR0 12 
J 0
(-11424 950);
DISPLAY 0.638298 (-11424 950);
PAINT MONO (-11424 950);
FORCEPROP 2 LAST PATH I484
J 0
(-11450 1000);
DISPLAY 0.680851 (-11450 1000);
DISPLAY INVISIBLE (-11450 1000);
FORCEPROP 1 LAST COMMENT_BODY TRUE
J 0
(-11075 875);
DISPLAY 0.872340 (-11075 875);
PAINT PEACH (-11075 875);
DISPLAY INVISIBLE (-11075 875);
FORCEPROP 1 LAST OFFPAGE TRUE
J 0
(-10850 825);
DISPLAY 0.872340 (-10850 825);
PAINT GREEN (-10850 825);
DISPLAY INVISIBLE (-10850 825);
FORCEPROP 2 LAST CDS_LIB standard
J 0
(-11175 950);
DISPLAY INVISIBLE (-11175 950);
FORCEADD OFFPAGE..1
(-11175 650);
FORCEPROP 2 LAST $XR0 12 
J 0
(-11426 650);
DISPLAY 0.638298 (-11426 650);
PAINT MONO (-11426 650);
FORCEPROP 2 LAST $XR1 27 
J 0
(-11516 650);
DISPLAY 0.638298 (-11516 650);
PAINT MONO (-11516 650);
FORCEPROP 2 LAST PATH I485
J 0
(-11425 700);
DISPLAY 0.680851 (-11425 700);
DISPLAY INVISIBLE (-11425 700);
FORCEPROP 1 LAST COMMENT_BODY TRUE
J 0
(-11050 550);
DISPLAY 0.872340 (-11050 550);
PAINT PEACH (-11050 550);
DISPLAY INVISIBLE (-11050 550);
FORCEPROP 1 LAST OFFPAGE TRUE
J 0
(-10850 525);
DISPLAY 0.872340 (-10850 525);
PAINT GREEN (-10850 525);
DISPLAY INVISIBLE (-10850 525);
FORCEPROP 2 LAST CDS_LIB standard
J 0
(-11175 650);
DISPLAY INVISIBLE (-11175 650);
FORCEADD OFFPAGE..6
(-11175 600);
FORCEPROP 2 LAST $XR1 27 
J 0
(-11514 600);
DISPLAY 0.638298 (-11514 600);
PAINT MONO (-11514 600);
FORCEPROP 2 LAST $XR0 12 
J 0
(-11424 600);
DISPLAY 0.638298 (-11424 600);
PAINT MONO (-11424 600);
FORCEPROP 2 LAST CDS_LIB standard
J 0
(-11175 600);
DISPLAY INVISIBLE (-11175 600);
FORCEPROP 1 LAST OFFPAGE TRUE
J 0
(-10850 475);
DISPLAY 0.872340 (-10850 475);
PAINT GREEN (-10850 475);
DISPLAY INVISIBLE (-10850 475);
FORCEPROP 1 LAST COMMENT_BODY TRUE
J 0
(-11075 525);
DISPLAY 0.872340 (-11075 525);
PAINT PEACH (-11075 525);
DISPLAY INVISIBLE (-11075 525);
FORCEPROP 2 LAST PATH I486
J 0
(-11450 650);
DISPLAY 0.680851 (-11450 650);
DISPLAY INVISIBLE (-11450 650);
FORCEADD OFFPAGE..1
(-11175 300);
FORCEPROP 2 LAST $XR0 12 
J 0
(-11426 300);
DISPLAY 0.638298 (-11426 300);
PAINT MONO (-11426 300);
FORCEPROP 2 LAST $XR1 27 
J 0
(-11516 300);
DISPLAY 0.638298 (-11516 300);
PAINT MONO (-11516 300);
FORCEPROP 2 LAST PATH I487
J 0
(-11425 350);
DISPLAY 0.680851 (-11425 350);
DISPLAY INVISIBLE (-11425 350);
FORCEPROP 1 LAST COMMENT_BODY TRUE
J 0
(-11050 200);
DISPLAY 0.872340 (-11050 200);
PAINT PEACH (-11050 200);
DISPLAY INVISIBLE (-11050 200);
FORCEPROP 1 LAST OFFPAGE TRUE
J 0
(-10850 175);
DISPLAY 0.872340 (-10850 175);
PAINT GREEN (-10850 175);
DISPLAY INVISIBLE (-10850 175);
FORCEPROP 2 LAST CDS_LIB standard
J 0
(-11175 300);
DISPLAY INVISIBLE (-11175 300);
FORCEADD OFFPAGE..6
(-11175 250);
FORCEPROP 2 LAST $XR1 27 
J 0
(-11514 250);
DISPLAY 0.638298 (-11514 250);
PAINT MONO (-11514 250);
FORCEPROP 2 LAST $XR0 12 
J 0
(-11424 250);
DISPLAY 0.638298 (-11424 250);
PAINT MONO (-11424 250);
FORCEPROP 2 LAST PATH I488
J 0
(-11450 300);
DISPLAY 0.680851 (-11450 300);
DISPLAY INVISIBLE (-11450 300);
FORCEPROP 1 LAST COMMENT_BODY TRUE
J 0
(-11075 175);
DISPLAY 0.872340 (-11075 175);
PAINT PEACH (-11075 175);
DISPLAY INVISIBLE (-11075 175);
FORCEPROP 1 LAST OFFPAGE TRUE
J 0
(-10850 125);
DISPLAY 0.872340 (-10850 125);
PAINT GREEN (-10850 125);
DISPLAY INVISIBLE (-10850 125);
FORCEPROP 2 LAST CDS_LIB standard
J 0
(-11175 250);
DISPLAY INVISIBLE (-11175 250);
FORCEADD OFFPAGE..6
(-11175 850);
FORCEPROP 2 LAST $XR0 12 
J 0
(-11424 850);
DISPLAY 0.638298 (-11424 850);
PAINT MONO (-11424 850);
FORCEPROP 2 LAST $XR1 27 
J 0
(-11514 850);
DISPLAY 0.638298 (-11514 850);
PAINT MONO (-11514 850);
FORCEPROP 2 LAST PATH I489
J 0
(-11450 900);
DISPLAY 0.680851 (-11450 900);
DISPLAY INVISIBLE (-11450 900);
FORCEPROP 1 LAST COMMENT_BODY TRUE
J 0
(-11075 775);
DISPLAY 0.872340 (-11075 775);
PAINT PEACH (-11075 775);
DISPLAY INVISIBLE (-11075 775);
FORCEPROP 1 LAST OFFPAGE TRUE
J 0
(-10850 725);
DISPLAY 0.872340 (-10850 725);
PAINT GREEN (-10850 725);
DISPLAY INVISIBLE (-10850 725);
FORCEPROP 2 LAST CDS_LIB standard
J 0
(-11175 850);
DISPLAY INVISIBLE (-11175 850);
FORCEADD OFFPAGE..1
(-11175 900);
FORCEPROP 2 LAST $XR0 12 
J 0
(-11426 900);
DISPLAY 0.638298 (-11426 900);
PAINT MONO (-11426 900);
FORCEPROP 2 LAST $XR1 27 
J 0
(-11516 900);
DISPLAY 0.638298 (-11516 900);
PAINT MONO (-11516 900);
FORCEPROP 2 LAST PATH I490
J 0
(-11425 950);
DISPLAY 0.680851 (-11425 950);
DISPLAY INVISIBLE (-11425 950);
FORCEPROP 1 LAST COMMENT_BODY TRUE
J 0
(-11050 800);
DISPLAY 0.872340 (-11050 800);
PAINT PEACH (-11050 800);
DISPLAY INVISIBLE (-11050 800);
FORCEPROP 1 LAST OFFPAGE TRUE
J 0
(-10850 775);
DISPLAY 0.872340 (-10850 775);
PAINT GREEN (-10850 775);
DISPLAY INVISIBLE (-10850 775);
FORCEPROP 2 LAST CDS_LIB standard
J 0
(-11175 900);
DISPLAY INVISIBLE (-11175 900);
FORCEADD OFFPAGE..6
(-11175 700);
FORCEPROP 2 LAST $XR1 27 
J 0
(-11514 700);
DISPLAY 0.638298 (-11514 700);
PAINT MONO (-11514 700);
FORCEPROP 2 LAST $XR0 12 
J 0
(-11424 700);
DISPLAY 0.638298 (-11424 700);
PAINT MONO (-11424 700);
FORCEPROP 2 LAST PATH I491
J 0
(-11450 750);
DISPLAY 0.680851 (-11450 750);
DISPLAY INVISIBLE (-11450 750);
FORCEPROP 1 LAST COMMENT_BODY TRUE
J 0
(-11075 625);
DISPLAY 0.872340 (-11075 625);
PAINT PEACH (-11075 625);
DISPLAY INVISIBLE (-11075 625);
FORCEPROP 1 LAST OFFPAGE TRUE
J 0
(-10850 575);
DISPLAY 0.872340 (-10850 575);
PAINT GREEN (-10850 575);
DISPLAY INVISIBLE (-10850 575);
FORCEPROP 2 LAST CDS_LIB standard
J 0
(-11175 700);
DISPLAY INVISIBLE (-11175 700);
FORCEADD OFFPAGE..1
(-11175 750);
FORCEPROP 2 LAST $XR1 27 
J 0
(-11486 750);
DISPLAY 0.638298 (-11486 750);
PAINT MONO (-11486 750);
FORCEPROP 2 LAST $XR0 12 
J 0
(-11396 750);
DISPLAY 0.638298 (-11396 750);
PAINT MONO (-11396 750);
FORCEPROP 2 LAST PATH I492
J 0
(-11425 800);
DISPLAY 0.680851 (-11425 800);
DISPLAY INVISIBLE (-11425 800);
FORCEPROP 1 LAST COMMENT_BODY TRUE
J 0
(-11050 650);
DISPLAY 0.872340 (-11050 650);
PAINT PEACH (-11050 650);
DISPLAY INVISIBLE (-11050 650);
FORCEPROP 1 LAST OFFPAGE TRUE
J 0
(-10850 625);
DISPLAY 0.872340 (-10850 625);
PAINT GREEN (-10850 625);
DISPLAY INVISIBLE (-10850 625);
FORCEPROP 2 LAST CDS_LIB standard
J 0
(-11175 750);
DISPLAY INVISIBLE (-11175 750);
FORCEADD OFFPAGE..1
(-11175 200);
FORCEPROP 2 LAST $XR1 27 
J 0
(-11516 200);
DISPLAY 0.638298 (-11516 200);
PAINT MONO (-11516 200);
FORCEPROP 2 LAST $XR0 12 
J 0
(-11426 200);
DISPLAY 0.638298 (-11426 200);
PAINT MONO (-11426 200);
FORCEPROP 2 LAST PATH I493
J 0
(-11425 250);
DISPLAY 0.680851 (-11425 250);
DISPLAY INVISIBLE (-11425 250);
FORCEPROP 1 LAST COMMENT_BODY TRUE
J 0
(-11050 100);
DISPLAY 0.872340 (-11050 100);
PAINT PEACH (-11050 100);
DISPLAY INVISIBLE (-11050 100);
FORCEPROP 1 LAST OFFPAGE TRUE
J 0
(-10850 75);
DISPLAY 0.872340 (-10850 75);
PAINT GREEN (-10850 75);
DISPLAY INVISIBLE (-10850 75);
FORCEPROP 2 LAST CDS_LIB standard
J 0
(-11175 200);
DISPLAY INVISIBLE (-11175 200);
FORCEADD OFFPAGE..6
(-11175 150);
FORCEPROP 2 LAST $XR0 12 
J 0
(-11424 150);
DISPLAY 0.638298 (-11424 150);
PAINT MONO (-11424 150);
FORCEPROP 2 LAST $XR1 27 
J 0
(-11514 150);
DISPLAY 0.638298 (-11514 150);
PAINT MONO (-11514 150);
FORCEPROP 1 LAST OFFPAGE TRUE
J 0
(-10850 25);
DISPLAY 0.872340 (-10850 25);
PAINT GREEN (-10850 25);
DISPLAY INVISIBLE (-10850 25);
FORCEPROP 1 LAST COMMENT_BODY TRUE
J 0
(-11075 75);
DISPLAY 0.872340 (-11075 75);
PAINT PEACH (-11075 75);
DISPLAY INVISIBLE (-11075 75);
FORCEPROP 2 LAST PATH I494
J 0
(-11450 200);
DISPLAY 0.680851 (-11450 200);
DISPLAY INVISIBLE (-11450 200);
FORCEPROP 2 LAST CDS_LIB standard
J 0
(-11175 150);
DISPLAY INVISIBLE (-11175 150);
FORCEADD OFFPAGE..2
(-5925 -200);
FORCEPROP 2 LAST $XR0 13 
J 0
(-5736 -200);
DISPLAY 0.638298 (-5736 -200);
PAINT MONO (-5736 -200);
FORCEPROP 2 LAST PATH I495
J 0
(-5625 -150);
DISPLAY 0.680851 (-5625 -150);
DISPLAY INVISIBLE (-5625 -150);
FORCEPROP 1 LAST COMMENT_BODY TRUE
J 0
(-5970 -295);
DISPLAY 0.872340 (-5970 -295);
PAINT PEACH (-5970 -295);
DISPLAY INVISIBLE (-5970 -295);
FORCEPROP 1 LAST OFFPAGE TRUE
J 0
(-5600 -325);
DISPLAY 0.872340 (-5600 -325);
PAINT GREEN (-5600 -325);
DISPLAY INVISIBLE (-5600 -325);
FORCEPROP 2 LAST CDS_LIB standard
J 0
(-5925 -200);
DISPLAY INVISIBLE (-5925 -200);
FORCEADD OFFPAGE..4
(-5925 -150);
FORCEPROP 2 LAST $XR0 13 
J 0
(-5739 -150);
DISPLAY 0.638298 (-5739 -150);
PAINT MONO (-5739 -150);
FORCEPROP 1 LAST OFFPAGE TRUE
J 0
(-5600 -275);
DISPLAY 0.872340 (-5600 -275);
PAINT GREEN (-5600 -275);
DISPLAY INVISIBLE (-5600 -275);
FORCEPROP 1 LAST COMMENT_BODY TRUE
J 0
(-5950 -250);
DISPLAY 0.872340 (-5950 -250);
PAINT PEACH (-5950 -250);
DISPLAY INVISIBLE (-5950 -250);
FORCEPROP 2 LAST PATH I496
J 0
(-5625 -100);
DISPLAY 0.680851 (-5625 -100);
DISPLAY INVISIBLE (-5625 -100);
FORCEPROP 2 LAST CDS_LIB standard
J 0
(-5925 -150);
DISPLAY INVISIBLE (-5925 -150);
FORCEADD OFFPAGE..2
(-5925 -100);
FORCEPROP 2 LAST $XR0 13 
J 0
(-5736 -100);
DISPLAY 0.638298 (-5736 -100);
PAINT MONO (-5736 -100);
FORCEPROP 2 LAST PATH I497
J 0
(-5625 -50);
DISPLAY 0.680851 (-5625 -50);
DISPLAY INVISIBLE (-5625 -50);
FORCEPROP 1 LAST COMMENT_BODY TRUE
J 0
(-5970 -195);
DISPLAY 0.872340 (-5970 -195);
PAINT PEACH (-5970 -195);
DISPLAY INVISIBLE (-5970 -195);
FORCEPROP 1 LAST OFFPAGE TRUE
J 0
(-5600 -225);
DISPLAY 0.872340 (-5600 -225);
PAINT GREEN (-5600 -225);
DISPLAY INVISIBLE (-5600 -225);
FORCEPROP 2 LAST CDS_LIB standard
J 0
(-5925 -100);
DISPLAY INVISIBLE (-5925 -100);
FORCEADD OFFPAGE..2
(-5925 -50);
FORCEPROP 2 LAST PATH I498
J 0
(-5625 0);
DISPLAY 0.680851 (-5625 0);
DISPLAY INVISIBLE (-5625 0);
FORCEPROP 1 LAST COMMENT_BODY TRUE
J 0
(-5970 -145);
DISPLAY 0.872340 (-5970 -145);
PAINT PEACH (-5970 -145);
DISPLAY INVISIBLE (-5970 -145);
FORCEPROP 1 LAST OFFPAGE TRUE
J 0
(-5600 -175);
DISPLAY 0.872340 (-5600 -175);
PAINT GREEN (-5600 -175);
DISPLAY INVISIBLE (-5600 -175);
FORCEPROP 2 LAST CDS_LIB standard
J 0
(-5925 -50);
DISPLAY INVISIBLE (-5925 -50);
FORCEADD OFFPAGE..2
(-5925 0);
FORCEPROP 2 LAST $XR0 13 
J 0
(-5736 0);
DISPLAY 0.638298 (-5736 0);
PAINT MONO (-5736 0);
FORCEPROP 2 LAST PATH I499
J 0
(-5625 50);
DISPLAY 0.680851 (-5625 50);
DISPLAY INVISIBLE (-5625 50);
FORCEPROP 2 LAST CDS_LIB standard
J 0
(-5925 0);
DISPLAY INVISIBLE (-5925 0);
FORCEPROP 1 LAST OFFPAGE TRUE
J 0
(-5600 -125);
DISPLAY 0.872340 (-5600 -125);
PAINT GREEN (-5600 -125);
DISPLAY INVISIBLE (-5600 -125);
FORCEPROP 1 LAST COMMENT_BODY TRUE
J 0
(-5970 -95);
DISPLAY 0.872340 (-5970 -95);
PAINT PEACH (-5970 -95);
DISPLAY INVISIBLE (-5970 -95);
FORCEADD OFFPAGE..2
(-5925 -250);
FORCEPROP 2 LAST $XR0 13 
J 0
(-5736 -250);
DISPLAY 0.638298 (-5736 -250);
PAINT MONO (-5736 -250);
FORCEPROP 2 LAST PATH I500
J 0
(-5625 -200);
DISPLAY 0.680851 (-5625 -200);
DISPLAY INVISIBLE (-5625 -200);
FORCEPROP 1 LAST COMMENT_BODY TRUE
J 0
(-5970 -345);
DISPLAY 0.872340 (-5970 -345);
PAINT PEACH (-5970 -345);
DISPLAY INVISIBLE (-5970 -345);
FORCEPROP 1 LAST OFFPAGE TRUE
J 0
(-5600 -375);
DISPLAY 0.872340 (-5600 -375);
PAINT GREEN (-5600 -375);
DISPLAY INVISIBLE (-5600 -375);
FORCEPROP 2 LAST CDS_LIB standard
J 0
(-5925 -250);
DISPLAY INVISIBLE (-5925 -250);
FORCEADD Q_CAP..1
(-4675 -50);
FORCEPROP 1 LAST TOLERANCE 10%
J 0
(-4600 -100);
DISPLAY 0.510638 (-4600 -100);
PAINT SKYBLUE (-4600 -100);
FORCEPROP 1 LAST MATERIAL EMPTY
J 0
(-4600 -150);
DISPLAY 0.510638 (-4600 -150);
PAINT RED (-4600 -150);
FORCEPROP 1 LAST VALUE 0.1UF
J 0
(-4600 0);
DISPLAY 0.510638 (-4600 0);
PAINT SKYBLUE (-4600 0);
FORCEPROP 1 LAST VOLTAGE 25V
J 0
(-4600 -50);
DISPLAY 0.510638 (-4600 -50);
PAINT SKYBLUE (-4600 -50);
FORCEPROP 1 LAST PACK_TYPE 0402
J 0
(-4600 -200);
DISPLAY 0.510638 (-4600 -200);
PAINT SKYBLUE (-4600 -200);
FORCEPROP 1 LAST PART_NUMBER CH4104K1B00
J 0
(-4600 -250);
DISPLAY 0.510638 (-4600 -250);
PAINT WHITE (-4600 -250);
FORCEPROP 2 LAST CDS_LIB pure_quanta
J 0
(-4675 -50);
DISPLAY INVISIBLE (-4675 -50);
FORCEPROP 2 LAST SEC_TYPE 0402
J 0
(-4625 150);
DISPLAY 0.680851 (-4625 150);
DISPLAY INVISIBLE (-4625 150);
FORCEPROP 1 LAST PATH I503
J 0
(-4625 100);
DISPLAY 0.978723 (-4625 100);
PAINT WHITE (-4625 100);
DISPLAY INVISIBLE (-4625 100);
FORCEPROP 1 LAST LOCATION C174
J 0
(-4600 50);
DISPLAY 0.702128 (-4600 50);
PAINT YELLOW (-4600 50);
FORCEPROP 1 LASTPIN (-4675 50) $PN 1
J 0
(-4665 30);
DISPLAY 0.808511 (-4665 30);
PAINT WHITE (-4665 30);
FORCEPROP 1 LASTPIN (-4675 -150) $PN 2
J 0
(-4665 -170);
DISPLAY 0.808511 (-4665 -170);
PAINT WHITE (-4665 -170);
FORCEPROP 2 LAST SEC 1
J 0
(-4625 150);
DISPLAY 0.680851 (-4625 150);
PAINT MONO (-4625 150);
DISPLAY INVISIBLE (-4625 150);
FORCEADD UNIVERSAL_GND..1
(-4675 -300);
FORCEPROP 3 LASTPIN (-4675 -250) SIG_NAME GND\g
J 0
(-4665 -240);
DISPLAY 0.659574 (-4665 -240);
PAINT MONO (-4665 -240);
DISPLAY INVISIBLE (-4665 -240);
FORCEPROP 2 LAST CDS_LIB logical_power
J 0
(-4675 -300);
DISPLAY INVISIBLE (-4675 -300);
FORCEPROP 1 LAST HDL_POWER GND
J 1
(-4650 -375);
DISPLAY 0.702128 (-4650 -375);
PAINT GREEN (-4650 -375);
DISPLAY INVISIBLE (-4650 -375);
FORCEPROP 1 LAST PATH I504
J 0
(-4600 -300);
DISPLAY 0.872340 (-4600 -300);
PAINT AQUA (-4600 -300);
DISPLAY INVISIBLE (-4600 -300);
FORCEADD OFFPAGE..1
R 2
(-5925 2750);
FORCEPROP 2 LAST $XR0 31 
J 0
(-5739 2750);
DISPLAY 0.638298 (-5739 2750);
PAINT MONO (-5739 2750);
FORCEPROP 2 LAST PATH I508
J 0
(-5725 2800);
DISPLAY 0.680851 (-5725 2800);
DISPLAY INVISIBLE (-5725 2800);
FORCEPROP 1 LAST COMMENT_BODY TRUE
J 2
(-6050 2650);
DISPLAY 0.872340 (-6050 2650);
PAINT PEACH (-6050 2650);
DISPLAY INVISIBLE (-6050 2650);
FORCEPROP 1 LAST OFFPAGE TRUE
J 2
(-6250 2625);
DISPLAY 0.872340 (-6250 2625);
PAINT GREEN (-6250 2625);
DISPLAY INVISIBLE (-6250 2625);
FORCEPROP 2 LAST CDS_LIB standard
J 0
(-5925 2750);
DISPLAY INVISIBLE (-5925 2750);
FORCEADD OFFPAGE..2
(-5925 2700);
FORCEPROP 2 LAST $XR0 31 
J 0
(-5736 2700);
DISPLAY 0.638298 (-5736 2700);
PAINT MONO (-5736 2700);
FORCEPROP 2 LAST CDS_LIB standard
J 0
(-5925 2700);
DISPLAY INVISIBLE (-5925 2700);
FORCEPROP 2 LAST PATH I509
J 0
(-5725 2750);
DISPLAY 0.680851 (-5725 2750);
DISPLAY INVISIBLE (-5725 2750);
FORCEPROP 1 LAST OFFPAGE TRUE
J 0
(-5600 2575);
DISPLAY 0.872340 (-5600 2575);
PAINT GREEN (-5600 2575);
DISPLAY INVISIBLE (-5600 2575);
FORCEPROP 1 LAST COMMENT_BODY TRUE
J 0
(-5970 2605);
DISPLAY 0.872340 (-5970 2605);
PAINT PEACH (-5970 2605);
DISPLAY INVISIBLE (-5970 2605);
FORCEADD OFFPAGE..2
(-5925 -850);
FORCEPROP 2 LAST $XR0 29 
J 0
(-5736 -850);
DISPLAY 0.638298 (-5736 -850);
PAINT MONO (-5736 -850);
FORCEPROP 1 LAST OFFPAGE TRUE
J 0
(-5600 -975);
DISPLAY 0.872340 (-5600 -975);
PAINT GREEN (-5600 -975);
DISPLAY INVISIBLE (-5600 -975);
FORCEPROP 1 LAST COMMENT_BODY TRUE
J 0
(-5970 -945);
DISPLAY 0.872340 (-5970 -945);
PAINT PEACH (-5970 -945);
DISPLAY INVISIBLE (-5970 -945);
FORCEPROP 2 LAST PATH I515
J 0
(-5725 -800);
DISPLAY 0.680851 (-5725 -800);
DISPLAY INVISIBLE (-5725 -800);
FORCEPROP 2 LAST CDS_LIB standard
J 0
(-5925 -850);
DISPLAY INVISIBLE (-5925 -850);
FORCEADD OFFPAGE..2
(-5925 -800);
FORCEPROP 2 LAST $XR0 29 
J 0
(-5736 -800);
DISPLAY 0.638298 (-5736 -800);
PAINT MONO (-5736 -800);
FORCEPROP 2 LAST CDS_LIB standard
J 0
(-5925 -800);
DISPLAY INVISIBLE (-5925 -800);
FORCEPROP 2 LAST PATH I516
J 0
(-5725 -750);
DISPLAY 0.680851 (-5725 -750);
DISPLAY INVISIBLE (-5725 -750);
FORCEPROP 1 LAST OFFPAGE TRUE
J 0
(-5600 -925);
DISPLAY 0.872340 (-5600 -925);
PAINT GREEN (-5600 -925);
DISPLAY INVISIBLE (-5600 -925);
FORCEPROP 1 LAST COMMENT_BODY TRUE
J 0
(-5970 -895);
DISPLAY 0.872340 (-5970 -895);
PAINT PEACH (-5970 -895);
DISPLAY INVISIBLE (-5970 -895);
FORCEADD OFFPAGE..1
(-11175 -800);
FORCEPROP 2 LAST $XR0 29 
J 0
(-11396 -800);
DISPLAY 0.638298 (-11396 -800);
PAINT MONO (-11396 -800);
FORCEPROP 1 LAST OFFPAGE TRUE
J 0
(-10850 -925);
DISPLAY 0.872340 (-10850 -925);
PAINT GREEN (-10850 -925);
DISPLAY INVISIBLE (-10850 -925);
FORCEPROP 1 LAST COMMENT_BODY TRUE
J 0
(-11050 -900);
DISPLAY 0.872340 (-11050 -900);
PAINT PEACH (-11050 -900);
DISPLAY INVISIBLE (-11050 -900);
FORCEPROP 2 LAST PATH I517
J 0
(-11425 -750);
DISPLAY 0.680851 (-11425 -750);
DISPLAY INVISIBLE (-11425 -750);
FORCEPROP 2 LAST CDS_LIB standard
J 0
(-11175 -800);
DISPLAY INVISIBLE (-11175 -800);
FORCEADD OFFPAGE..1
(-11175 -850);
FORCEPROP 2 LAST $XR0 29 
J 0
(-11396 -850);
DISPLAY 0.638298 (-11396 -850);
PAINT MONO (-11396 -850);
FORCEPROP 1 LAST OFFPAGE TRUE
J 0
(-10850 -975);
DISPLAY 0.872340 (-10850 -975);
PAINT GREEN (-10850 -975);
DISPLAY INVISIBLE (-10850 -975);
FORCEPROP 1 LAST COMMENT_BODY TRUE
J 0
(-11050 -950);
DISPLAY 0.872340 (-11050 -950);
PAINT PEACH (-11050 -950);
DISPLAY INVISIBLE (-11050 -950);
FORCEPROP 2 LAST PATH I518
J 0
(-11425 -800);
DISPLAY 0.680851 (-11425 -800);
DISPLAY INVISIBLE (-11425 -800);
FORCEPROP 2 LAST CDS_LIB standard
J 0
(-11175 -850);
DISPLAY INVISIBLE (-11175 -850);
FORCEADD OFFPAGE..5
(-11200 -1100);
FORCEPROP 2 LAST $XR0 12 
J 0
(-11424 -1100);
DISPLAY 0.638298 (-11424 -1100);
PAINT MONO (-11424 -1100);
FORCEPROP 2 LAST CDS_LIB standard
J 0
(-11200 -1100);
DISPLAY INVISIBLE (-11200 -1100);
FORCEPROP 2 LAST PATH I522
J 0
(-11150 -1025);
DISPLAY 0.680851 (-11150 -1025);
DISPLAY INVISIBLE (-11150 -1025);
FORCEPROP 1 LAST OFFPAGE TRUE
J 0
(-10875 -1225);
DISPLAY 0.872340 (-10875 -1225);
PAINT GREEN (-10875 -1225);
DISPLAY INVISIBLE (-10875 -1225);
FORCEPROP 1 LAST COMMENT_BODY TRUE
J 0
(-11100 -1175);
DISPLAY 0.872340 (-11100 -1175);
PAINT PEACH (-11100 -1175);
DISPLAY INVISIBLE (-11100 -1175);
FORCEADD OFFPAGE..5
(-11200 -1150);
FORCEPROP 2 LAST $XR0 12 
J 0
(-11424 -1150);
DISPLAY 0.638298 (-11424 -1150);
PAINT MONO (-11424 -1150);
FORCEPROP 2 LAST CDS_LIB standard
J 0
(-11200 -1150);
DISPLAY INVISIBLE (-11200 -1150);
FORCEPROP 2 LAST PATH I523
J 0
(-11150 -1075);
DISPLAY 0.680851 (-11150 -1075);
DISPLAY INVISIBLE (-11150 -1075);
FORCEPROP 1 LAST OFFPAGE TRUE
J 0
(-10875 -1275);
DISPLAY 0.872340 (-10875 -1275);
PAINT GREEN (-10875 -1275);
DISPLAY INVISIBLE (-10875 -1275);
FORCEPROP 1 LAST COMMENT_BODY TRUE
J 0
(-11100 -1225);
DISPLAY 0.872340 (-11100 -1225);
PAINT PEACH (-11100 -1225);
DISPLAY INVISIBLE (-11100 -1225);
FORCEADD OFFPAGE..6
(-11175 1650);
FORCEPROP 2 LAST $XR0 12 
J 0
(-11424 1650);
DISPLAY 0.638298 (-11424 1650);
PAINT MONO (-11424 1650);
FORCEPROP 2 LAST PATH I531
J 0
(-11125 1725);
DISPLAY 0.680851 (-11125 1725);
DISPLAY INVISIBLE (-11125 1725);
FORCEPROP 2 LAST CDS_LIB standard
J 0
(-11175 1650);
DISPLAY INVISIBLE (-11175 1650);
FORCEPROP 1 LAST OFFPAGE TRUE
J 0
(-10850 1525);
DISPLAY 0.872340 (-10850 1525);
PAINT GREEN (-10850 1525);
DISPLAY INVISIBLE (-10850 1525);
FORCEPROP 1 LAST COMMENT_BODY TRUE
J 0
(-11075 1575);
DISPLAY 0.872340 (-11075 1575);
PAINT PEACH (-11075 1575);
DISPLAY INVISIBLE (-11075 1575);
FORCEADD OFFPAGE..1
(-11175 1700);
FORCEPROP 2 LAST $XR0 12 
J 0
(-11426 1700);
DISPLAY 0.638298 (-11426 1700);
PAINT MONO (-11426 1700);
FORCEPROP 2 LAST PATH I532
J 0
(-11125 1775);
DISPLAY 0.680851 (-11125 1775);
DISPLAY INVISIBLE (-11125 1775);
FORCEPROP 2 LAST CDS_LIB standard
J 0
(-11175 1700);
DISPLAY INVISIBLE (-11175 1700);
FORCEPROP 1 LAST OFFPAGE TRUE
J 0
(-10850 1575);
DISPLAY 0.872340 (-10850 1575);
PAINT GREEN (-10850 1575);
DISPLAY INVISIBLE (-10850 1575);
FORCEPROP 1 LAST COMMENT_BODY TRUE
J 0
(-11050 1600);
DISPLAY 0.872340 (-11050 1600);
PAINT PEACH (-11050 1600);
DISPLAY INVISIBLE (-11050 1600);
FORCEADD OFFPAGE..5
(-11175 1550);
FORCEPROP 2 LAST $XR0 12 
J 0
(-11429 1550);
DISPLAY 0.638298 (-11429 1550);
PAINT MONO (-11429 1550);
FORCEPROP 2 LAST PATH I533
J 0
(-11125 1625);
DISPLAY 0.680851 (-11125 1625);
DISPLAY INVISIBLE (-11125 1625);
FORCEPROP 1 LAST COMMENT_BODY TRUE
J 0
(-11075 1475);
DISPLAY 0.872340 (-11075 1475);
PAINT PEACH (-11075 1475);
DISPLAY INVISIBLE (-11075 1475);
FORCEPROP 1 LAST OFFPAGE TRUE
J 0
(-10850 1425);
DISPLAY 0.872340 (-10850 1425);
PAINT GREEN (-10850 1425);
DISPLAY INVISIBLE (-10850 1425);
FORCEPROP 2 LAST CDS_LIB standard
J 0
(-11175 1550);
DISPLAY INVISIBLE (-11175 1550);
FORCEADD OFFPAGE..5
(-11175 1500);
FORCEPROP 2 LAST $XR0 12 
J 0
(-11429 1500);
DISPLAY 0.638298 (-11429 1500);
PAINT MONO (-11429 1500);
FORCEPROP 2 LAST PATH I534
J 0
(-11125 1575);
DISPLAY 0.680851 (-11125 1575);
DISPLAY INVISIBLE (-11125 1575);
FORCEPROP 1 LAST COMMENT_BODY TRUE
J 0
(-11075 1425);
DISPLAY 0.872340 (-11075 1425);
PAINT PEACH (-11075 1425);
DISPLAY INVISIBLE (-11075 1425);
FORCEPROP 1 LAST OFFPAGE TRUE
J 0
(-10850 1375);
DISPLAY 0.872340 (-10850 1375);
PAINT GREEN (-10850 1375);
DISPLAY INVISIBLE (-10850 1375);
FORCEPROP 2 LAST CDS_LIB standard
J 0
(-11175 1500);
DISPLAY INVISIBLE (-11175 1500);
FORCEADD OFFPAGE..5
(-10875 1350);
FORCEPROP 2 LAST $XR0 12 
J 0
(-11129 1350);
DISPLAY 0.638298 (-11129 1350);
PAINT MONO (-11129 1350);
FORCEPROP 2 LAST CDS_LIB standard
J 0
(-10875 1350);
DISPLAY INVISIBLE (-10875 1350);
FORCEPROP 1 LAST OFFPAGE TRUE
J 0
(-10550 1225);
DISPLAY 0.872340 (-10550 1225);
PAINT GREEN (-10550 1225);
DISPLAY INVISIBLE (-10550 1225);
FORCEPROP 1 LAST COMMENT_BODY TRUE
J 0
(-10775 1275);
DISPLAY 0.872340 (-10775 1275);
PAINT PEACH (-10775 1275);
DISPLAY INVISIBLE (-10775 1275);
FORCEPROP 2 LAST PATH I535
J 0
(-10825 1425);
DISPLAY 0.680851 (-10825 1425);
DISPLAY INVISIBLE (-10825 1425);
FORCEADD OFFPAGE..5
(-10875 1400);
FORCEPROP 2 LAST $XR0 12 
J 0
(-11129 1400);
DISPLAY 0.638298 (-11129 1400);
PAINT MONO (-11129 1400);
FORCEPROP 2 LAST CDS_LIB standard
J 0
(-10875 1400);
DISPLAY INVISIBLE (-10875 1400);
FORCEPROP 1 LAST OFFPAGE TRUE
J 0
(-10550 1275);
DISPLAY 0.872340 (-10550 1275);
PAINT GREEN (-10550 1275);
DISPLAY INVISIBLE (-10550 1275);
FORCEPROP 1 LAST COMMENT_BODY TRUE
J 0
(-10775 1325);
DISPLAY 0.872340 (-10775 1325);
PAINT PEACH (-10775 1325);
DISPLAY INVISIBLE (-10775 1325);
FORCEPROP 2 LAST PATH I536
J 0
(-10825 1475);
DISPLAY 0.680851 (-10825 1475);
DISPLAY INVISIBLE (-10825 1475);
FORCEADD OFFPAGE..1
(-10875 1200);
FORCEPROP 2 LAST $XR0 12 
J 0
(-11096 1200);
DISPLAY 0.638298 (-11096 1200);
PAINT MONO (-11096 1200);
FORCEPROP 2 LAST CDS_LIB standard
J 0
(-10875 1200);
DISPLAY INVISIBLE (-10875 1200);
FORCEPROP 1 LAST OFFPAGE TRUE
J 0
(-10550 1075);
DISPLAY 0.872340 (-10550 1075);
PAINT GREEN (-10550 1075);
DISPLAY INVISIBLE (-10550 1075);
FORCEPROP 1 LAST COMMENT_BODY TRUE
J 0
(-10750 1100);
DISPLAY 0.872340 (-10750 1100);
PAINT PEACH (-10750 1100);
DISPLAY INVISIBLE (-10750 1100);
FORCEPROP 2 LAST PATH I537
J 0
(-10825 1275);
DISPLAY 0.680851 (-10825 1275);
DISPLAY INVISIBLE (-10825 1275);
FORCEADD OFFPAGE..1
(-10875 1250);
FORCEPROP 2 LAST $XR0 12 
J 0
(-11096 1250);
DISPLAY 0.638298 (-11096 1250);
PAINT MONO (-11096 1250);
FORCEPROP 2 LAST CDS_LIB standard
J 0
(-10875 1250);
DISPLAY INVISIBLE (-10875 1250);
FORCEPROP 1 LAST OFFPAGE TRUE
J 0
(-10550 1125);
DISPLAY 0.872340 (-10550 1125);
PAINT GREEN (-10550 1125);
DISPLAY INVISIBLE (-10550 1125);
FORCEPROP 1 LAST COMMENT_BODY TRUE
J 0
(-10750 1150);
DISPLAY 0.872340 (-10750 1150);
PAINT PEACH (-10750 1150);
DISPLAY INVISIBLE (-10750 1150);
FORCEPROP 2 LAST PATH I538
J 0
(-10825 1325);
DISPLAY 0.680851 (-10825 1325);
DISPLAY INVISIBLE (-10825 1325);
FORCEADD OFFPAGE..5
(-11200 -1250);
FORCEPROP 2 LAST $XR0 12 
J 0
(-11424 -1250);
DISPLAY 0.638298 (-11424 -1250);
PAINT MONO (-11424 -1250);
FORCEPROP 2 LAST PATH I541
J 0
(-11150 -1175);
DISPLAY 0.680851 (-11150 -1175);
DISPLAY INVISIBLE (-11150 -1175);
FORCEPROP 2 LAST CDS_LIB standard
J 0
(-11200 -1250);
DISPLAY INVISIBLE (-11200 -1250);
FORCEPROP 1 LAST COMMENT_BODY TRUE
J 0
(-11100 -1325);
DISPLAY 0.872340 (-11100 -1325);
PAINT PEACH (-11100 -1325);
DISPLAY INVISIBLE (-11100 -1325);
FORCEPROP 1 LAST OFFPAGE TRUE
J 0
(-10875 -1375);
DISPLAY 0.872340 (-10875 -1375);
PAINT GREEN (-10875 -1375);
DISPLAY INVISIBLE (-10875 -1375);
FORCEADD OFFPAGE..5
(-11200 -1300);
FORCEPROP 2 LAST $XR0 12 
J 0
(-11424 -1300);
DISPLAY 0.638298 (-11424 -1300);
PAINT MONO (-11424 -1300);
FORCEPROP 2 LAST PATH I542
J 0
(-11150 -1225);
DISPLAY 0.680851 (-11150 -1225);
DISPLAY INVISIBLE (-11150 -1225);
FORCEPROP 2 LAST CDS_LIB standard
J 0
(-11200 -1300);
DISPLAY INVISIBLE (-11200 -1300);
FORCEPROP 1 LAST COMMENT_BODY TRUE
J 0
(-11100 -1375);
DISPLAY 0.872340 (-11100 -1375);
PAINT PEACH (-11100 -1375);
DISPLAY INVISIBLE (-11100 -1375);
FORCEPROP 1 LAST OFFPAGE TRUE
J 0
(-10875 -1425);
DISPLAY 0.872340 (-10875 -1425);
PAINT GREEN (-10875 -1425);
DISPLAY INVISIBLE (-10875 -1425);
FORCEADD OFFPAGE..4
(-5925 -1100);
FORCEPROP 2 LAST $XR0 12 
J 0
(-5739 -1100);
DISPLAY 0.638298 (-5739 -1100);
PAINT MONO (-5739 -1100);
FORCEPROP 2 LAST CDS_LIB standard
J 0
(-5925 -1100);
DISPLAY INVISIBLE (-5925 -1100);
FORCEPROP 2 LAST PATH I543
J 0
(-5750 -1025);
DISPLAY 0.680851 (-5750 -1025);
DISPLAY INVISIBLE (-5750 -1025);
FORCEPROP 1 LAST OFFPAGE TRUE
J 0
(-5600 -1225);
DISPLAY 0.872340 (-5600 -1225);
PAINT GREEN (-5600 -1225);
DISPLAY INVISIBLE (-5600 -1225);
FORCEPROP 1 LAST COMMENT_BODY TRUE
J 0
(-5950 -1200);
DISPLAY 0.872340 (-5950 -1200);
PAINT PEACH (-5950 -1200);
DISPLAY INVISIBLE (-5950 -1200);
FORCEADD OFFPAGE..4
(-5925 -1150);
FORCEPROP 2 LAST $XR0 12 
J 0
(-5739 -1150);
DISPLAY 0.638298 (-5739 -1150);
PAINT MONO (-5739 -1150);
FORCEPROP 1 LAST OFFPAGE TRUE
J 0
(-5600 -1275);
DISPLAY 0.872340 (-5600 -1275);
PAINT GREEN (-5600 -1275);
DISPLAY INVISIBLE (-5600 -1275);
FORCEPROP 1 LAST COMMENT_BODY TRUE
J 0
(-5950 -1250);
DISPLAY 0.872340 (-5950 -1250);
PAINT PEACH (-5950 -1250);
DISPLAY INVISIBLE (-5950 -1250);
FORCEPROP 2 LAST PATH I544
J 0
(-5750 -1075);
DISPLAY 0.680851 (-5750 -1075);
DISPLAY INVISIBLE (-5750 -1075);
FORCEPROP 2 LAST CDS_LIB standard
J 0
(-5925 -1150);
DISPLAY INVISIBLE (-5925 -1150);
FORCEADD FCONN168_ME1016810202011_SCM..1
(-8275 800);
FORCEPROP 1 LAST PART_NUMBER GOLD244
J 0
(-8891 3192);
DISPLAY 0.723404 (-8891 3192);
PAINT GREEN (-8891 3192);
FORCEPROP 2 LAST PART_TYPE SMLF
J 0
(-8875 3425);
DISPLAY 0.680851 (-8875 3425);
FORCEPROP 1 LAST MATERIAL EMPTY
J 0
(-8891 3065);
DISPLAY 0.723404 (-8891 3065);
PAINT GREEN (-8891 3065);
FORCEPROP 2 LAST VALUE FCONN168_ME1016810202011_SCM
J 0
(-8875 3375);
DISPLAY 0.680851 (-8875 3375);
FORCEPROP 2 LAST CDS_LIB pure_quanta
J 0
(-8275 800);
DISPLAY INVISIBLE (-8275 800);
FORCEPROP 1 LAST PATH I553
J 0
(-8275 800);
DISPLAY 0.723404 (-8275 800);
PAINT GREEN (-8275 800);
DISPLAY INVISIBLE (-8275 800);
FORCEPROP 1 LAST CDS_LMAN_SYM_OUTLINE -625,2250,625,-2250
J 0
(-8275 800);
DISPLAY 0.468085 (-8275 800);
PAINT GREEN (-8275 800);
DISPLAY INVISIBLE (-8275 800);
FORCEPROP 1 LAST NEEDS_NO_SIZE TRUE
J 0
(-8275 800);
DISPLAY 0.723404 (-8275 800);
PAINT GREEN (-8275 800);
DISPLAY INVISIBLE (-8275 800);
FORCEPROP 1 LAST $LOCATION GF1
J 0
(-8891 3339);
DISPLAY 0.723404 (-8891 3339);
PAINT GREEN (-8891 3339);
FORCEPROP 0 LASTPIN (-9050 -550) $PN A54
J 2
(-9060 -540);
DISPLAY 0.680851 (-9060 -540);
PAINT MONO (-9060 -540);
FORCEPROP 0 LASTPIN (-9050 1500) $PN A15
J 2
(-9060 1510);
DISPLAY 0.680851 (-9060 1510);
PAINT MONO (-9060 1510);
FORCEPROP 0 LASTPIN (-9050 1550) $PN A14
J 2
(-9060 1560);
DISPLAY 0.680851 (-9060 1560);
PAINT MONO (-9060 1560);
FORCEPROP 0 LASTPIN (-9050 -350) $PN A50
J 2
(-9060 -340);
DISPLAY 0.680851 (-9060 -340);
PAINT MONO (-9060 -340);
FORCEPROP 0 LASTPIN (-9050 -300) $PN A49
J 2
(-9060 -290);
DISPLAY 0.680851 (-9060 -290);
PAINT MONO (-9060 -290);
FORCEPROP 0 LASTPIN (-7500 2100) $PN B3
J 0
(-7490 2110);
DISPLAY 0.680851 (-7490 2110);
PAINT MONO (-7490 2110);
FORCEPROP 0 LASTPIN (-7500 2200) $PN B1
J 0
(-7490 2210);
DISPLAY 0.680851 (-7490 2210);
PAINT MONO (-7490 2210);
FORCEPROP 0 LASTPIN (-7500 2150) $PN B2
J 0
(-7490 2160);
DISPLAY 0.680851 (-7490 2160);
PAINT MONO (-7490 2160);
FORCEPROP 0 LASTPIN (-7500 2000) $PN B5
J 0
(-7490 2010);
DISPLAY 0.680851 (-7490 2010);
PAINT MONO (-7490 2010);
FORCEPROP 0 LASTPIN (-7500 1950) $PN B6
J 0
(-7490 1960);
DISPLAY 0.680851 (-7490 1960);
PAINT MONO (-7490 1960);
FORCEPROP 0 LASTPIN (-7500 1900) $PN B7
J 0
(-7490 1910);
DISPLAY 0.680851 (-7490 1910);
PAINT MONO (-7490 1910);
FORCEPROP 0 LASTPIN (-7500 1850) $PN B8
J 0
(-7490 1860);
DISPLAY 0.680851 (-7490 1860);
PAINT MONO (-7490 1860);
FORCEPROP 0 LASTPIN (-7500 2050) $PN B4
J 0
(-7490 2060);
DISPLAY 0.680851 (-7490 2060);
PAINT MONO (-7490 2060);
FORCEPROP 0 LASTPIN (-9050 1600) $PN A13
J 2
(-9060 1610);
DISPLAY 0.680851 (-9060 1610);
PAINT MONO (-9060 1610);
FORCEPROP 0 LASTPIN (-9050 1450) $PN A16
J 2
(-9060 1460);
DISPLAY 0.680851 (-9060 1460);
PAINT MONO (-9060 1460);
FORCEPROP 0 LASTPIN (-9050 1300) $PN A19
J 2
(-9060 1310);
DISPLAY 0.680851 (-9060 1310);
PAINT MONO (-9060 1310);
FORCEPROP 0 LASTPIN (-9050 1150) $PN A22
J 2
(-9060 1160);
DISPLAY 0.680851 (-9060 1160);
PAINT MONO (-9060 1160);
FORCEPROP 0 LASTPIN (-9050 550) $PN A33
J 2
(-9060 560);
DISPLAY 0.680851 (-9060 560);
PAINT MONO (-9060 560);
FORCEPROP 0 LASTPIN (-9050 100) $PN A42
J 2
(-9060 110);
DISPLAY 0.680851 (-9060 110);
PAINT MONO (-9060 110);
FORCEPROP 0 LASTPIN (-9050 -750) $PN A58
J 2
(-9060 -740);
DISPLAY 0.680851 (-9060 -740);
PAINT MONO (-9060 -740);
FORCEPROP 0 LASTPIN (-9050 -900) $PN A61
J 2
(-9060 -890);
DISPLAY 0.680851 (-9060 -890);
PAINT MONO (-9060 -890);
FORCEPROP 0 LASTPIN (-9050 -1050) $PN A64
J 2
(-9060 -1040);
DISPLAY 0.680851 (-9060 -1040);
PAINT MONO (-9060 -1040);
FORCEPROP 0 LASTPIN (-9050 -1200) $PN A67
J 2
(-9060 -1190);
DISPLAY 0.680851 (-9060 -1190);
PAINT MONO (-9060 -1190);
FORCEPROP 0 LASTPIN (-9050 -1350) $PN A70
J 2
(-9060 -1340);
DISPLAY 0.680851 (-9060 -1340);
PAINT MONO (-9060 -1340);
FORCEPROP 0 LASTPIN (-7500 1750) $PN B10
J 0
(-7490 1760);
DISPLAY 0.680851 (-7490 1760);
PAINT MONO (-7490 1760);
FORCEPROP 0 LASTPIN (-7500 1400) $PN B17
J 0
(-7490 1410);
DISPLAY 0.680851 (-7490 1410);
PAINT MONO (-7490 1410);
FORCEPROP 0 LASTPIN (-7500 950) $PN B26
J 0
(-7490 960);
DISPLAY 0.680851 (-7490 960);
PAINT MONO (-7490 960);
FORCEPROP 0 LASTPIN (-7500 550) $PN B33
J 0
(-7490 560);
DISPLAY 0.680851 (-7490 560);
PAINT MONO (-7490 560);
FORCEPROP 0 LASTPIN (-7500 300) $PN B38
J 0
(-7490 310);
DISPLAY 0.680851 (-7490 310);
PAINT MONO (-7490 310);
FORCEPROP 0 LASTPIN (-7500 -300) $PN B49
J 0
(-7490 -290);
DISPLAY 0.680851 (-7490 -290);
PAINT MONO (-7490 -290);
FORCEPROP 0 LASTPIN (-7500 -450) $PN B52
J 0
(-7490 -440);
DISPLAY 0.680851 (-7490 -440);
PAINT MONO (-7490 -440);
FORCEPROP 0 LASTPIN (-7500 -600) $PN B55
J 0
(-7490 -590);
DISPLAY 0.680851 (-7490 -590);
PAINT MONO (-7490 -590);
FORCEPROP 0 LASTPIN (-7500 -750) $PN B58
J 0
(-7490 -740);
DISPLAY 0.680851 (-7490 -740);
PAINT MONO (-7490 -740);
FORCEPROP 0 LASTPIN (-7500 -900) $PN B61
J 0
(-7490 -890);
DISPLAY 0.680851 (-7490 -890);
PAINT MONO (-7490 -890);
FORCEPROP 0 LASTPIN (-7500 -1050) $PN B64
J 0
(-7490 -1040);
DISPLAY 0.680851 (-7490 -1040);
PAINT MONO (-7490 -1040);
FORCEPROP 0 LASTPIN (-7500 -1200) $PN B67
J 0
(-7490 -1190);
DISPLAY 0.680851 (-7490 -1190);
PAINT MONO (-7490 -1190);
FORCEPROP 0 LASTPIN (-7500 -1350) $PN B70
J 0
(-7490 -1340);
DISPLAY 0.680851 (-7490 -1340);
PAINT MONO (-7490 -1340);
FORCEPROP 0 LASTPIN (-9050 2850) $PN OA3
J 2
(-9060 2860);
DISPLAY 0.680851 (-9060 2860);
PAINT MONO (-9060 2860);
FORCEPROP 0 LASTPIN (-9050 2800) $PN OA4
J 2
(-9060 2810);
DISPLAY 0.680851 (-9060 2810);
PAINT MONO (-9060 2810);
FORCEPROP 0 LASTPIN (-9050 2350) $PN OA13
J 2
(-9060 2360);
DISPLAY 0.680851 (-9060 2360);
PAINT MONO (-9060 2360);
FORCEPROP 0 LASTPIN (-7500 2800) $PN OB4
J 0
(-7490 2810);
DISPLAY 0.680851 (-7490 2810);
PAINT MONO (-7490 2810);
FORCEPROP 0 LASTPIN (-7500 2650) $PN OB7
J 0
(-7490 2660);
DISPLAY 0.680851 (-7490 2660);
PAINT MONO (-7490 2660);
FORCEPROP 0 LASTPIN (-7500 2500) $PN OB10
J 0
(-7490 2510);
DISPLAY 0.680851 (-7490 2510);
PAINT MONO (-7490 2510);
FORCEPROP 0 LASTPIN (-9050 0) $PN A43
J 2
(-9060 10);
DISPLAY 0.680851 (-9060 10);
PAINT MONO (-9060 10);
FORCEPROP 0 LASTPIN (-9050 -100) $PN A45
J 2
(-9060 -90);
DISPLAY 0.680851 (-9060 -90);
PAINT MONO (-9060 -90);
FORCEPROP 0 LASTPIN (-9050 -50) $PN A44
J 2
(-9060 -40);
DISPLAY 0.680851 (-9060 -40);
PAINT MONO (-9060 -40);
FORCEPROP 0 LASTPIN (-9050 -150) $PN A46
J 2
(-9060 -140);
DISPLAY 0.680851 (-9060 -140);
PAINT MONO (-9060 -140);
FORCEPROP 0 LASTPIN (-9050 2200) $PN A1
J 2
(-9060 2210);
DISPLAY 0.680851 (-9060 2210);
PAINT MONO (-9060 2210);
FORCEPROP 0 LASTPIN (-9050 2150) $PN A2
J 2
(-9060 2160);
DISPLAY 0.680851 (-9060 2160);
PAINT MONO (-9060 2160);
FORCEPROP 0 LASTPIN (-9050 2100) $PN A3
J 2
(-9060 2110);
DISPLAY 0.680851 (-9060 2110);
PAINT MONO (-9060 2110);
FORCEPROP 0 LASTPIN (-9050 2050) $PN A4
J 2
(-9060 2060);
DISPLAY 0.680851 (-9060 2060);
PAINT MONO (-9060 2060);
FORCEPROP 0 LASTPIN (-9050 2000) $PN A5
J 2
(-9060 2010);
DISPLAY 0.680851 (-9060 2010);
PAINT MONO (-9060 2010);
FORCEPROP 0 LASTPIN (-9050 1950) $PN A6
J 2
(-9060 1960);
DISPLAY 0.680851 (-9060 1960);
PAINT MONO (-9060 1960);
FORCEPROP 0 LASTPIN (-9050 1900) $PN A7
J 2
(-9060 1910);
DISPLAY 0.680851 (-9060 1910);
PAINT MONO (-9060 1910);
FORCEPROP 0 LASTPIN (-9050 1850) $PN A8
J 2
(-9060 1860);
DISPLAY 0.680851 (-9060 1860);
PAINT MONO (-9060 1860);
FORCEPROP 0 LASTPIN (-9050 1800) $PN A9
J 2
(-9060 1810);
DISPLAY 0.680851 (-9060 1810);
PAINT MONO (-9060 1810);
FORCEPROP 0 LASTPIN (-9050 1750) $PN A10
J 2
(-9060 1760);
DISPLAY 0.680851 (-9060 1760);
PAINT MONO (-9060 1760);
FORCEPROP 0 LASTPIN (-9050 1700) $PN A11
J 2
(-9060 1710);
DISPLAY 0.680851 (-9060 1710);
PAINT MONO (-9060 1710);
FORCEPROP 0 LASTPIN (-9050 1650) $PN A12
J 2
(-9060 1660);
DISPLAY 0.680851 (-9060 1660);
PAINT MONO (-9060 1660);
FORCEPROP 0 LASTPIN (-9050 1100) $PN A23
J 2
(-9060 1110);
DISPLAY 0.680851 (-9060 1110);
PAINT MONO (-9060 1110);
FORCEPROP 0 LASTPIN (-9050 1050) $PN A24
J 2
(-9060 1060);
DISPLAY 0.680851 (-9060 1060);
PAINT MONO (-9060 1060);
FORCEPROP 0 LASTPIN (-9050 1000) $PN A25
J 2
(-9060 1010);
DISPLAY 0.680851 (-9060 1010);
PAINT MONO (-9060 1010);
FORCEPROP 0 LASTPIN (-9050 950) $PN A26
J 2
(-9060 960);
DISPLAY 0.680851 (-9060 960);
PAINT MONO (-9060 960);
FORCEPROP 0 LASTPIN (-9050 900) $PN A27
J 2
(-9060 910);
DISPLAY 0.680851 (-9060 910);
PAINT MONO (-9060 910);
FORCEPROP 0 LASTPIN (-9050 850) $PN A28
J 2
(-9060 860);
DISPLAY 0.680851 (-9060 860);
PAINT MONO (-9060 860);
FORCEPROP 0 LASTPIN (-9050 750) $PN A29
J 2
(-9060 760);
DISPLAY 0.680851 (-9060 760);
PAINT MONO (-9060 760);
FORCEPROP 0 LASTPIN (-9050 700) $PN A30
J 2
(-9060 710);
DISPLAY 0.680851 (-9060 710);
PAINT MONO (-9060 710);
FORCEPROP 0 LASTPIN (-9050 650) $PN A31
J 2
(-9060 660);
DISPLAY 0.680851 (-9060 660);
PAINT MONO (-9060 660);
FORCEPROP 0 LASTPIN (-9050 600) $PN A32
J 2
(-9060 610);
DISPLAY 0.680851 (-9060 610);
PAINT MONO (-9060 610);
FORCEPROP 0 LASTPIN (-9050 300) $PN A38
J 2
(-9060 310);
DISPLAY 0.680851 (-9060 310);
PAINT MONO (-9060 310);
FORCEPROP 0 LASTPIN (-9050 250) $PN A39
J 2
(-9060 260);
DISPLAY 0.680851 (-9060 260);
PAINT MONO (-9060 260);
FORCEPROP 0 LASTPIN (-9050 200) $PN A40
J 2
(-9060 210);
DISPLAY 0.680851 (-9060 210);
PAINT MONO (-9060 210);
FORCEPROP 0 LASTPIN (-9050 150) $PN A41
J 2
(-9060 160);
DISPLAY 0.680851 (-9060 160);
PAINT MONO (-9060 160);
FORCEPROP 0 LASTPIN (-9050 2750) $PN OA5
J 2
(-9060 2760);
DISPLAY 0.680851 (-9060 2760);
PAINT MONO (-9060 2760);
FORCEPROP 0 LASTPIN (-9050 2700) $PN OA6
J 2
(-9060 2710);
DISPLAY 0.680851 (-9060 2710);
PAINT MONO (-9060 2710);
FORCEPROP 0 LASTPIN (-9050 2650) $PN OA7
J 2
(-9060 2660);
DISPLAY 0.680851 (-9060 2660);
PAINT MONO (-9060 2660);
FORCEPROP 0 LASTPIN (-9050 2600) $PN OA8
J 2
(-9060 2610);
DISPLAY 0.680851 (-9060 2610);
PAINT MONO (-9060 2610);
FORCEPROP 0 LASTPIN (-9050 2550) $PN OA9
J 2
(-9060 2560);
DISPLAY 0.680851 (-9060 2560);
PAINT MONO (-9060 2560);
FORCEPROP 0 LASTPIN (-9050 2500) $PN OA10
J 2
(-9060 2510);
DISPLAY 0.680851 (-9060 2510);
PAINT MONO (-9060 2510);
FORCEPROP 0 LASTPIN (-9050 2450) $PN OA11
J 2
(-9060 2460);
DISPLAY 0.680851 (-9060 2460);
PAINT MONO (-9060 2460);
FORCEPROP 0 LASTPIN (-9050 2400) $PN OA12
J 2
(-9060 2410);
DISPLAY 0.680851 (-9060 2410);
PAINT MONO (-9060 2410);
FORCEPROP 0 LASTPIN (-9050 -650) $PN A56
J 2
(-9060 -640);
DISPLAY 0.680851 (-9060 -640);
PAINT MONO (-9060 -640);
FORCEPROP 0 LASTPIN (-9050 500) $PN A34
J 2
(-9060 510);
DISPLAY 0.680851 (-9060 510);
PAINT MONO (-9060 510);
FORCEPROP 0 LASTPIN (-9050 400) $PN A36
J 2
(-9060 410);
DISPLAY 0.680851 (-9060 410);
PAINT MONO (-9060 410);
FORCEPROP 0 LASTPIN (-9050 350) $PN A37
J 2
(-9060 360);
DISPLAY 0.680851 (-9060 360);
PAINT MONO (-9060 360);
FORCEPROP 0 LASTPIN (-9050 450) $PN A35
J 2
(-9060 460);
DISPLAY 0.680851 (-9060 460);
PAINT MONO (-9060 460);
FORCEPROP 0 LASTPIN (-7500 1350) $PN B18
J 0
(-7490 1360);
DISPLAY 0.680851 (-7490 1360);
PAINT MONO (-7490 1360);
FORCEPROP 0 LASTPIN (-7500 1300) $PN B19
J 0
(-7490 1310);
DISPLAY 0.680851 (-7490 1310);
PAINT MONO (-7490 1310);
FORCEPROP 0 LASTPIN (-7500 1050) $PN B24
J 0
(-7490 1060);
DISPLAY 0.680851 (-7490 1060);
PAINT MONO (-7490 1060);
FORCEPROP 0 LASTPIN (-7500 1000) $PN B25
J 0
(-7490 1010);
DISPLAY 0.680851 (-7490 1010);
PAINT MONO (-7490 1010);
FORCEPROP 0 LASTPIN (-7500 1100) $PN B23
J 0
(-7490 1110);
DISPLAY 0.680851 (-7490 1110);
PAINT MONO (-7490 1110);
FORCEPROP 0 LASTPIN (-7500 1200) $PN B21
J 0
(-7490 1210);
DISPLAY 0.680851 (-7490 1210);
PAINT MONO (-7490 1210);
FORCEPROP 0 LASTPIN (-7500 1150) $PN B22
J 0
(-7490 1160);
DISPLAY 0.680851 (-7490 1160);
PAINT MONO (-7490 1160);
FORCEPROP 0 LASTPIN (-7500 1250) $PN B20
J 0
(-7490 1260);
DISPLAY 0.680851 (-7490 1260);
PAINT MONO (-7490 1260);
FORCEPROP 0 LASTPIN (-7500 150) $PN B41
J 0
(-7490 160);
DISPLAY 0.680851 (-7490 160);
PAINT MONO (-7490 160);
FORCEPROP 0 LASTPIN (-9050 2950) $PN OA1
J 2
(-9060 2960);
DISPLAY 0.680851 (-9060 2960);
PAINT MONO (-9060 2960);
FORCEPROP 0 LASTPIN (-9050 2900) $PN OA2
J 2
(-9060 2910);
DISPLAY 0.680851 (-9060 2910);
PAINT MONO (-9060 2910);
FORCEPROP 0 LASTPIN (-7500 2950) $PN OB1
J 0
(-7490 2960);
DISPLAY 0.680851 (-7490 2960);
PAINT MONO (-7490 2960);
FORCEPROP 0 LASTPIN (-7500 2900) $PN OB2
J 0
(-7490 2910);
DISPLAY 0.680851 (-7490 2910);
PAINT MONO (-7490 2910);
FORCEPROP 0 LASTPIN (-9050 1200) $PN A21
J 2
(-9060 1210);
DISPLAY 0.680851 (-9060 1210);
PAINT MONO (-9060 1210);
FORCEPROP 0 LASTPIN (-9050 1250) $PN A20
J 2
(-9060 1260);
DISPLAY 0.680851 (-9060 1260);
PAINT MONO (-9060 1260);
FORCEPROP 0 LASTPIN (-9050 1350) $PN A18
J 2
(-9060 1360);
DISPLAY 0.680851 (-9060 1360);
PAINT MONO (-9060 1360);
FORCEPROP 0 LASTPIN (-9050 1400) $PN A17
J 2
(-9060 1410);
DISPLAY 0.680851 (-9060 1410);
PAINT MONO (-9060 1410);
FORCEPROP 0 LASTPIN (-9050 -850) $PN A60
J 2
(-9060 -840);
DISPLAY 0.680851 (-9060 -840);
PAINT MONO (-9060 -840);
FORCEPROP 0 LASTPIN (-9050 -1000) $PN A63
J 2
(-9060 -990);
DISPLAY 0.680851 (-9060 -990);
PAINT MONO (-9060 -990);
FORCEPROP 0 LASTPIN (-9050 -1150) $PN A66
J 2
(-9060 -1140);
DISPLAY 0.680851 (-9060 -1140);
PAINT MONO (-9060 -1140);
FORCEPROP 0 LASTPIN (-9050 -1300) $PN A69
J 2
(-9060 -1290);
DISPLAY 0.680851 (-9060 -1290);
PAINT MONO (-9060 -1290);
FORCEPROP 0 LASTPIN (-9050 -800) $PN A59
J 2
(-9060 -790);
DISPLAY 0.680851 (-9060 -790);
PAINT MONO (-9060 -790);
FORCEPROP 0 LASTPIN (-9050 -950) $PN A62
J 2
(-9060 -940);
DISPLAY 0.680851 (-9060 -940);
PAINT MONO (-9060 -940);
FORCEPROP 0 LASTPIN (-9050 -1100) $PN A65
J 2
(-9060 -1090);
DISPLAY 0.680851 (-9060 -1090);
PAINT MONO (-9060 -1090);
FORCEPROP 0 LASTPIN (-9050 -1250) $PN A68
J 2
(-9060 -1240);
DISPLAY 0.680851 (-9060 -1240);
PAINT MONO (-9060 -1240);
FORCEPROP 0 LASTPIN (-7500 -850) $PN B60
J 0
(-7490 -840);
DISPLAY 0.680851 (-7490 -840);
PAINT MONO (-7490 -840);
FORCEPROP 0 LASTPIN (-7500 -1000) $PN B63
J 0
(-7490 -990);
DISPLAY 0.680851 (-7490 -990);
PAINT MONO (-7490 -990);
FORCEPROP 0 LASTPIN (-7500 -1150) $PN B66
J 0
(-7490 -1140);
DISPLAY 0.680851 (-7490 -1140);
PAINT MONO (-7490 -1140);
FORCEPROP 0 LASTPIN (-7500 -1300) $PN B69
J 0
(-7490 -1290);
DISPLAY 0.680851 (-7490 -1290);
PAINT MONO (-7490 -1290);
FORCEPROP 0 LASTPIN (-7500 -800) $PN B59
J 0
(-7490 -790);
DISPLAY 0.680851 (-7490 -790);
PAINT MONO (-7490 -790);
FORCEPROP 0 LASTPIN (-7500 -950) $PN B62
J 0
(-7490 -940);
DISPLAY 0.680851 (-7490 -940);
PAINT MONO (-7490 -940);
FORCEPROP 0 LASTPIN (-7500 -1100) $PN B65
J 0
(-7490 -1090);
DISPLAY 0.680851 (-7490 -1090);
PAINT MONO (-7490 -1090);
FORCEPROP 0 LASTPIN (-7500 -1250) $PN B68
J 0
(-7490 -1240);
DISPLAY 0.680851 (-7490 -1240);
PAINT MONO (-7490 -1240);
FORCEPROP 0 LASTPIN (-7500 900) $PN B27
J 0
(-7490 910);
DISPLAY 0.680851 (-7490 910);
PAINT MONO (-7490 910);
FORCEPROP 0 LASTPIN (-7500 2850) $PN OB3
J 0
(-7490 2860);
DISPLAY 0.680851 (-7490 2860);
PAINT MONO (-7490 2860);
FORCEPROP 0 LASTPIN (-9050 -700) $PN A57
J 2
(-9060 -690);
DISPLAY 0.680851 (-9060 -690);
PAINT MONO (-9060 -690);
FORCEPROP 0 LASTPIN (-7500 850) $PN B28
J 0
(-7490 860);
DISPLAY 0.680851 (-7490 860);
PAINT MONO (-7490 860);
FORCEPROP 0 LASTPIN (-7500 1700) $PN B11
J 0
(-7490 1710);
DISPLAY 0.680851 (-7490 1710);
PAINT MONO (-7490 1710);
FORCEPROP 0 LASTPIN (-7500 1650) $PN B12
J 0
(-7490 1660);
DISPLAY 0.680851 (-7490 1660);
PAINT MONO (-7490 1660);
FORCEPROP 0 LASTPIN (-7500 100) $PN B42
J 0
(-7490 110);
DISPLAY 0.680851 (-7490 110);
PAINT MONO (-7490 110);
FORCEPROP 0 LASTPIN (-7500 1600) $PN B13
J 0
(-7490 1610);
DISPLAY 0.680851 (-7490 1610);
PAINT MONO (-7490 1610);
FORCEPROP 0 LASTPIN (-7500 1550) $PN B14
J 0
(-7490 1560);
DISPLAY 0.680851 (-7490 1560);
PAINT MONO (-7490 1560);
FORCEPROP 0 LASTPIN (-7500 1500) $PN B15
J 0
(-7490 1510);
DISPLAY 0.680851 (-7490 1510);
PAINT MONO (-7490 1510);
FORCEPROP 0 LASTPIN (-7500 1450) $PN B16
J 0
(-7490 1460);
DISPLAY 0.680851 (-7490 1460);
PAINT MONO (-7490 1460);
FORCEPROP 0 LASTPIN (-7500 0) $PN B43
J 0
(-7490 10);
DISPLAY 0.680851 (-7490 10);
PAINT MONO (-7490 10);
FORCEPROP 0 LASTPIN (-7500 -50) $PN B44
J 0
(-7490 -40);
DISPLAY 0.680851 (-7490 -40);
PAINT MONO (-7490 -40);
FORCEPROP 0 LASTPIN (-7500 -100) $PN B45
J 0
(-7490 -90);
DISPLAY 0.680851 (-7490 -90);
PAINT MONO (-7490 -90);
FORCEPROP 0 LASTPIN (-7500 -150) $PN B46
J 0
(-7490 -140);
DISPLAY 0.680851 (-7490 -140);
PAINT MONO (-7490 -140);
FORCEPROP 0 LASTPIN (-7500 -200) $PN B47
J 0
(-7490 -190);
DISPLAY 0.680851 (-7490 -190);
PAINT MONO (-7490 -190);
FORCEPROP 0 LASTPIN (-7500 -250) $PN B48
J 0
(-7490 -240);
DISPLAY 0.680851 (-7490 -240);
PAINT MONO (-7490 -240);
FORCEPROP 0 LASTPIN (-9050 -500) $PN A53
J 2
(-9060 -490);
DISPLAY 0.680851 (-9060 -490);
PAINT MONO (-9060 -490);
FORCEPROP 0 LASTPIN (-9050 -400) $PN A51
J 2
(-9060 -390);
DISPLAY 0.680851 (-9060 -390);
PAINT MONO (-9060 -390);
FORCEPROP 0 LASTPIN (-7500 -650) $PN B56
J 0
(-7490 -640);
DISPLAY 0.680851 (-7490 -640);
PAINT MONO (-7490 -640);
FORCEPROP 0 LASTPIN (-7500 -700) $PN B57
J 0
(-7490 -690);
DISPLAY 0.680851 (-7490 -690);
PAINT MONO (-7490 -690);
FORCEPROP 0 LASTPIN (-7500 450) $PN B35
J 0
(-7490 460);
DISPLAY 0.680851 (-7490 460);
PAINT MONO (-7490 460);
FORCEPROP 0 LASTPIN (-7500 1800) $PN B9
J 0
(-7490 1810);
DISPLAY 0.680851 (-7490 1810);
PAINT MONO (-7490 1810);
FORCEPROP 0 LASTPIN (-7500 650) $PN B31
J 0
(-7490 660);
DISPLAY 0.680851 (-7490 660);
PAINT MONO (-7490 660);
FORCEPROP 0 LASTPIN (-7500 750) $PN B29
J 0
(-7490 760);
DISPLAY 0.680851 (-7490 760);
PAINT MONO (-7490 760);
FORCEPROP 0 LASTPIN (-7500 600) $PN B32
J 0
(-7490 610);
DISPLAY 0.680851 (-7490 610);
PAINT MONO (-7490 610);
FORCEPROP 0 LASTPIN (-7500 400) $PN B36
J 0
(-7490 410);
DISPLAY 0.680851 (-7490 410);
PAINT MONO (-7490 410);
FORCEPROP 0 LASTPIN (-7500 500) $PN B34
J 0
(-7490 510);
DISPLAY 0.680851 (-7490 510);
PAINT MONO (-7490 510);
FORCEPROP 0 LASTPIN (-7500 350) $PN B37
J 0
(-7490 360);
DISPLAY 0.680851 (-7490 360);
PAINT MONO (-7490 360);
FORCEPROP 0 LASTPIN (-7500 700) $PN B30
J 0
(-7490 710);
DISPLAY 0.680851 (-7490 710);
PAINT MONO (-7490 710);
FORCEPROP 0 LASTPIN (-7500 200) $PN B40
J 0
(-7490 210);
DISPLAY 0.680851 (-7490 210);
PAINT MONO (-7490 210);
FORCEPROP 0 LASTPIN (-7500 250) $PN B39
J 0
(-7490 260);
DISPLAY 0.680851 (-7490 260);
PAINT MONO (-7490 260);
FORCEPROP 0 LASTPIN (-9050 -600) $PN A55
J 2
(-9060 -590);
DISPLAY 0.680851 (-9060 -590);
PAINT MONO (-9060 -590);
FORCEPROP 0 LASTPIN (-9050 -450) $PN A52
J 2
(-9060 -440);
DISPLAY 0.680851 (-9060 -440);
PAINT MONO (-9060 -440);
FORCEPROP 0 LASTPIN (-7500 2450) $PN OB11
J 0
(-7490 2460);
DISPLAY 0.680851 (-7490 2460);
PAINT MONO (-7490 2460);
FORCEPROP 0 LASTPIN (-7500 2400) $PN OB12
J 0
(-7490 2410);
DISPLAY 0.680851 (-7490 2410);
PAINT MONO (-7490 2410);
FORCEPROP 0 LASTPIN (-7500 2300) $PN OB14
J 0
(-7490 2310);
DISPLAY 0.680851 (-7490 2310);
PAINT MONO (-7490 2310);
FORCEPROP 0 LASTPIN (-7500 2350) $PN OB13
J 0
(-7490 2360);
DISPLAY 0.680851 (-7490 2360);
PAINT MONO (-7490 2360);
FORCEPROP 0 LASTPIN (-9050 -200) $PN A47
J 2
(-9060 -190);
DISPLAY 0.680851 (-9060 -190);
PAINT MONO (-9060 -190);
FORCEPROP 0 LASTPIN (-9050 -250) $PN A48
J 2
(-9060 -240);
DISPLAY 0.680851 (-9060 -240);
PAINT MONO (-9060 -240);
FORCEPROP 0 LASTPIN (-7500 2550) $PN OB9
J 0
(-7490 2560);
DISPLAY 0.680851 (-7490 2560);
PAINT MONO (-7490 2560);
FORCEPROP 0 LASTPIN (-7500 2600) $PN OB8
J 0
(-7490 2610);
DISPLAY 0.680851 (-7490 2610);
PAINT MONO (-7490 2610);
FORCEPROP 0 LASTPIN (-7500 2700) $PN OB6
J 0
(-7490 2710);
DISPLAY 0.680851 (-7490 2710);
PAINT MONO (-7490 2710);
FORCEPROP 0 LASTPIN (-7500 2750) $PN OB5
J 0
(-7490 2760);
DISPLAY 0.680851 (-7490 2760);
PAINT MONO (-7490 2760);
FORCEPROP 0 LASTPIN (-7500 -550) $PN B54
J 0
(-7490 -540);
DISPLAY 0.680851 (-7490 -540);
PAINT MONO (-7490 -540);
FORCEPROP 0 LASTPIN (-7500 -500) $PN B53
J 0
(-7490 -490);
DISPLAY 0.680851 (-7490 -490);
PAINT MONO (-7490 -490);
FORCEPROP 0 LASTPIN (-7500 -400) $PN B51
J 0
(-7490 -390);
DISPLAY 0.680851 (-7490 -390);
PAINT MONO (-7490 -390);
FORCEPROP 0 LASTPIN (-7500 -350) $PN B50
J 0
(-7490 -340);
DISPLAY 0.680851 (-7490 -340);
PAINT MONO (-7490 -340);
FORCEPROP 0 LASTPIN (-9050 2300) $PN OA14
J 2
(-9060 2310);
DISPLAY 0.680851 (-9060 2310);
PAINT MONO (-9060 2310);
FORCEPROP 0 LAST CDS_LOCATION GF1
J 0
(-8875 3475);
DISPLAY 0.680851 (-8875 3475);
DISPLAY INVISIBLE (-8875 3475);
FORCEPROP 0 LAST $SEC 1
J 0
(-8875 3475);
DISPLAY 0.680851 (-8875 3475);
PAINT MONO (-8875 3475);
DISPLAY INVISIBLE (-8875 3475);
FORCEPROP 0 LAST CDS_SEC 1
J 0
(-8875 3475);
DISPLAY 0.680851 (-8875 3475);
DISPLAY INVISIBLE (-8875 3475);
FORCEADD OFFPAGE..1
(-11175 0);
FORCEPROP 2 LAST $XR0 13 
J 0
(-11396 0);
DISPLAY 0.638298 (-11396 0);
PAINT MONO (-11396 0);
FORCEPROP 2 LAST CDS_LIB standard
J 0
(-11175 0);
DISPLAY INVISIBLE (-11175 0);
FORCEPROP 1 LAST OFFPAGE TRUE
J 0
(-10850 -125);
DISPLAY 0.872340 (-10850 -125);
PAINT GREEN (-10850 -125);
DISPLAY INVISIBLE (-10850 -125);
FORCEPROP 1 LAST COMMENT_BODY TRUE
J 0
(-11050 -100);
DISPLAY 0.872340 (-11050 -100);
PAINT PEACH (-11050 -100);
DISPLAY INVISIBLE (-11050 -100);
FORCEPROP 2 LAST PATH I554
J 0
(-11425 50);
DISPLAY 0.680851 (-11425 50);
DISPLAY INVISIBLE (-11425 50);
FORCEADD OFFPAGE..2
(-5925 2050);
FORCEPROP 2 LAST $XR0 12 
J 0
(-5736 2050);
DISPLAY 0.638298 (-5736 2050);
PAINT MONO (-5736 2050);
FORCEPROP 2 LAST CDS_LIB standard
J 0
(-5925 2050);
DISPLAY INVISIBLE (-5925 2050);
FORCEPROP 2 LAST PATH I555
J 0
(-5750 2125);
DISPLAY 0.680851 (-5750 2125);
DISPLAY INVISIBLE (-5750 2125);
FORCEPROP 1 LAST COMMENT_BODY TRUE
J 0
(-5970 1955);
DISPLAY 0.872340 (-5970 1955);
PAINT PEACH (-5970 1955);
DISPLAY INVISIBLE (-5970 1955);
FORCEPROP 1 LAST OFFPAGE TRUE
J 0
(-5600 1925);
DISPLAY 0.872340 (-5600 1925);
PAINT GREEN (-5600 1925);
DISPLAY INVISIBLE (-5600 1925);
FORCEADD Q_RES..1
(-10350 2000);
FORCEPROP 1 LAST VALUE 33.2
J 0
(-10250 2000);
DISPLAY 0.510638 (-10250 2000);
PAINT SKYBLUE (-10250 2000);
FORCEPROP 1 LAST MATERIAL CHIP
J 2
(-10050 2000);
DISPLAY 0.510638 (-10050 2000);
PAINT SKYBLUE (-10050 2000);
FORCEPROP 1 LAST PACK_TYPE 0402LF
J 0
(-10100 1850);
DISPLAY 0.510638 (-10100 1850);
PAINT SKYBLUE (-10100 1850);
DISPLAY INVISIBLE (-10100 1850);
FORCEPROP 1 LAST WATTAGE 1/16W
J 2
(-10375 1850);
DISPLAY 0.510638 (-10375 1850);
PAINT SKYBLUE (-10375 1850);
DISPLAY INVISIBLE (-10375 1850);
FORCEPROP 1 LAST PART_NUMBER CS03322FB03
J 0
(-10400 2100);
DISPLAY 0.510638 (-10400 2100);
PAINT WHITE (-10400 2100);
DISPLAY INVISIBLE (-10400 2100);
FORCEPROP 1 LAST TOLERANCE 1%
J 0
(-10225 2000);
DISPLAY 0.510638 (-10225 2000);
PAINT SKYBLUE (-10225 2000);
DISPLAY INVISIBLE (-10225 2000);
FORCEPROP 1 LAST PATH I557
J 0
(-10400 2150);
DISPLAY 0.978723 (-10400 2150);
PAINT WHITE (-10400 2150);
DISPLAY INVISIBLE (-10400 2150);
FORCEPROP 2 LAST CDS_LIB pure_quanta
J 0
(-10350 2000);
DISPLAY INVISIBLE (-10350 2000);
FORCEPROP 1 LAST $LOCATION R455
J 2
(-10425 2000);
DISPLAY 0.702128 (-10425 2000);
PAINT YELLOW (-10425 2000);
FORCEPROP 1 LASTPIN (-10450 2000) $PN 1
J 0
(-10438 2012);
DISPLAY 0.787234 (-10438 2012);
PAINT MONO (-10438 2012);
FORCEPROP 1 LASTPIN (-10250 2000) $PN 2
J 0
(-10288 2012);
DISPLAY 0.787234 (-10288 2012);
PAINT MONO (-10288 2012);
FORCEPROP 0 LAST CDS_LOCATION R455
J 0
(-10425 2050);
DISPLAY 0.680851 (-10425 2050);
DISPLAY INVISIBLE (-10425 2050);
FORCEPROP 0 LAST $SEC 1
J 0
(-10425 2050);
DISPLAY 0.680851 (-10425 2050);
PAINT MONO (-10425 2050);
DISPLAY INVISIBLE (-10425 2050);
FORCEPROP 0 LAST CDS_SEC 1
J 0
(-10425 2050);
DISPLAY 0.680851 (-10425 2050);
DISPLAY INVISIBLE (-10425 2050);
FORCEADD OFFPAGE..6
(-11175 2000);
FORCEPROP 2 LAST $XR0 12 
J 0
(-11424 2000);
DISPLAY 0.638298 (-11424 2000);
PAINT MONO (-11424 2000);
FORCEPROP 2 LAST $XR1 27 
J 0
(-11514 2000);
DISPLAY 0.638298 (-11514 2000);
PAINT MONO (-11514 2000);
FORCEPROP 2 LAST $XR2 26 
J 0
(-11604 2000);
DISPLAY 0.638298 (-11604 2000);
PAINT MONO (-11604 2000);
FORCEPROP 2 LAST CDS_LIB standard
J 0
(-11175 2000);
DISPLAY INVISIBLE (-11175 2000);
FORCEPROP 1 LAST OFFPAGE TRUE
J 0
(-10850 1875);
DISPLAY 0.872340 (-10850 1875);
PAINT GREEN (-10850 1875);
DISPLAY INVISIBLE (-10850 1875);
FORCEPROP 1 LAST COMMENT_BODY TRUE
J 0
(-11075 1925);
DISPLAY 0.872340 (-11075 1925);
PAINT PEACH (-11075 1925);
DISPLAY INVISIBLE (-11075 1925);
FORCEPROP 2 LAST PATH I558
J 0
(-11400 2050);
DISPLAY 0.680851 (-11400 2050);
DISPLAY INVISIBLE (-11400 2050);
FORCEADD OFFPAGE..1
R 2
(-5925 2600);
FORCEPROP 2 LAST $XR0 31 
J 0
(-5739 2600);
DISPLAY 0.638298 (-5739 2600);
PAINT MONO (-5739 2600);
FORCEPROP 1 LAST OFFPAGE TRUE
J 2
(-6250 2475);
DISPLAY 0.872340 (-6250 2475);
PAINT GREEN (-6250 2475);
DISPLAY INVISIBLE (-6250 2475);
FORCEPROP 1 LAST COMMENT_BODY TRUE
J 2
(-6050 2500);
DISPLAY 0.872340 (-6050 2500);
PAINT PEACH (-6050 2500);
DISPLAY INVISIBLE (-6050 2500);
FORCEPROP 2 LAST PATH I560
J 0
(-5750 2675);
DISPLAY 0.680851 (-5750 2675);
DISPLAY INVISIBLE (-5750 2675);
FORCEPROP 2 LAST CDS_LIB standard
J 0
(-5925 2600);
DISPLAY INVISIBLE (-5925 2600);
FORCEADD Q_RES..1
R 2
(-6450 -1250);
FORCEPROP 1 LAST VALUE 0
J 2
(-6325 -1250);
DISPLAY 0.510638 (-6325 -1250);
PAINT RED (-6325 -1250);
FORCEPROP 1 LAST MATERIAL EMPTY
J 0
(-6300 -1250);
DISPLAY 0.510638 (-6300 -1250);
PAINT RED (-6300 -1250);
FORCEPROP 1 LAST PACK_TYPE 0402LF
J 2
(-6275 -1275);
DISPLAY 0.510638 (-6275 -1275);
PAINT SKYBLUE (-6275 -1275);
DISPLAY INVISIBLE (-6275 -1275);
FORCEPROP 1 LAST TOLERANCE 5%
J 2
(-6475 -1275);
DISPLAY 0.510638 (-6475 -1275);
PAINT SKYBLUE (-6475 -1275);
DISPLAY INVISIBLE (-6475 -1275);
FORCEPROP 1 LAST WATTAGE 1/16W
J 0
(-6700 -1275);
DISPLAY 0.510638 (-6700 -1275);
PAINT SKYBLUE (-6700 -1275);
DISPLAY INVISIBLE (-6700 -1275);
FORCEPROP 2 LAST CDS_LIB pure_quanta
J 0
(-6450 -1250);
DISPLAY INVISIBLE (-6450 -1250);
FORCEPROP 1 LAST PATH I562
J 2
(-6400 -1100);
DISPLAY 0.978723 (-6400 -1100);
PAINT WHITE (-6400 -1100);
DISPLAY INVISIBLE (-6400 -1100);
FORCEPROP 1 LAST PART_NUMBER CS00002JB13
J 2
(-6500 -1300);
DISPLAY 0.510638 (-6500 -1300);
PAINT WHITE (-6500 -1300);
DISPLAY INVISIBLE (-6500 -1300);
FORCEPROP 1 LAST $LOCATION R564
J 2
(-6550 -1250);
DISPLAY 0.702128 (-6550 -1250);
PAINT YELLOW (-6550 -1250);
FORCEPROP 1 LASTPIN (-6350 -1250) $PN 1
J 2
(-6362 -1238);
DISPLAY 0.787234 (-6362 -1238);
PAINT MONO (-6362 -1238);
FORCEPROP 1 LASTPIN (-6550 -1250) $PN 2
J 2
(-6512 -1238);
DISPLAY 0.787234 (-6512 -1238);
PAINT MONO (-6512 -1238);
FORCEPROP 0 LAST CDS_LOCATION R564
J 0
(-6475 -1200);
DISPLAY 0.680851 (-6475 -1200);
DISPLAY INVISIBLE (-6475 -1200);
FORCEPROP 0 LAST $SEC 1
J 0
(-6475 -1200);
DISPLAY 0.680851 (-6475 -1200);
PAINT MONO (-6475 -1200);
DISPLAY INVISIBLE (-6475 -1200);
FORCEPROP 0 LAST CDS_SEC 1
J 0
(-6475 -1200);
DISPLAY 0.680851 (-6475 -1200);
DISPLAY INVISIBLE (-6475 -1200);
FORCEADD OFFPAGE..2
(-5475 -1250);
FORCEPROP 2 LAST $XR0 49 
J 0
(-5286 -1250);
DISPLAY 0.638298 (-5286 -1250);
PAINT MONO (-5286 -1250);
FORCEPROP 1 LAST COMMENT_BODY TRUE
J 0
(-5520 -1345);
DISPLAY 0.872340 (-5520 -1345);
PAINT PEACH (-5520 -1345);
DISPLAY INVISIBLE (-5520 -1345);
FORCEPROP 1 LAST OFFPAGE TRUE
J 0
(-5150 -1375);
DISPLAY 0.872340 (-5150 -1375);
PAINT GREEN (-5150 -1375);
DISPLAY INVISIBLE (-5150 -1375);
FORCEPROP 2 LAST CDS_LIB standard
J 0
(-5475 -1250);
DISPLAY INVISIBLE (-5475 -1250);
FORCEPROP 2 LAST PATH I563
J 0
(-5275 -1200);
DISPLAY 0.680851 (-5275 -1200);
DISPLAY INVISIBLE (-5275 -1200);
FORCEADD OFFPAGE..2
(-5475 -1300);
FORCEPROP 2 LAST $XR0 49 
J 0
(-5286 -1300);
DISPLAY 0.638298 (-5286 -1300);
PAINT MONO (-5286 -1300);
FORCEPROP 2 LAST PATH I564
J 0
(-5275 -1250);
DISPLAY 0.680851 (-5275 -1250);
DISPLAY INVISIBLE (-5275 -1250);
FORCEPROP 2 LAST CDS_LIB standard
J 0
(-5475 -1300);
DISPLAY INVISIBLE (-5475 -1300);
FORCEPROP 1 LAST OFFPAGE TRUE
J 0
(-5150 -1425);
DISPLAY 0.872340 (-5150 -1425);
PAINT GREEN (-5150 -1425);
DISPLAY INVISIBLE (-5150 -1425);
FORCEPROP 1 LAST COMMENT_BODY TRUE
J 0
(-5520 -1395);
DISPLAY 0.872340 (-5520 -1395);
PAINT PEACH (-5520 -1395);
DISPLAY INVISIBLE (-5520 -1395);
FORCEADD Q_RES..1
R 2
(-6450 -1300);
FORCEPROP 1 LAST VALUE 0
J 2
(-6325 -1300);
DISPLAY 0.510638 (-6325 -1300);
PAINT RED (-6325 -1300);
FORCEPROP 1 LAST MATERIAL EMPTY
J 0
(-6300 -1300);
DISPLAY 0.510638 (-6300 -1300);
PAINT RED (-6300 -1300);
FORCEPROP 2 LAST CDS_LIB pure_quanta
J 0
(-6450 -1300);
DISPLAY INVISIBLE (-6450 -1300);
FORCEPROP 1 LAST PATH I565
J 2
(-6400 -1150);
DISPLAY 0.978723 (-6400 -1150);
PAINT WHITE (-6400 -1150);
DISPLAY INVISIBLE (-6400 -1150);
FORCEPROP 1 LAST PART_NUMBER CS00002JB13
J 2
(-6500 -1350);
DISPLAY 0.510638 (-6500 -1350);
PAINT WHITE (-6500 -1350);
DISPLAY INVISIBLE (-6500 -1350);
FORCEPROP 1 LAST WATTAGE 1/16W
J 0
(-6700 -1325);
DISPLAY 0.510638 (-6700 -1325);
PAINT SKYBLUE (-6700 -1325);
DISPLAY INVISIBLE (-6700 -1325);
FORCEPROP 1 LAST TOLERANCE 5%
J 2
(-6475 -1325);
DISPLAY 0.510638 (-6475 -1325);
PAINT SKYBLUE (-6475 -1325);
DISPLAY INVISIBLE (-6475 -1325);
FORCEPROP 1 LAST PACK_TYPE 0402LF
J 2
(-6275 -1325);
DISPLAY 0.510638 (-6275 -1325);
PAINT SKYBLUE (-6275 -1325);
DISPLAY INVISIBLE (-6275 -1325);
FORCEPROP 1 LAST $LOCATION R811
J 2
(-6550 -1300);
DISPLAY 0.702128 (-6550 -1300);
PAINT YELLOW (-6550 -1300);
FORCEPROP 1 LASTPIN (-6350 -1300) $PN 1
J 2
(-6362 -1288);
DISPLAY 0.787234 (-6362 -1288);
PAINT MONO (-6362 -1288);
FORCEPROP 1 LASTPIN (-6550 -1300) $PN 2
J 2
(-6512 -1288);
DISPLAY 0.787234 (-6512 -1288);
PAINT MONO (-6512 -1288);
FORCEPROP 0 LAST CDS_LOCATION R811
J 0
(-6475 -1250);
DISPLAY 0.680851 (-6475 -1250);
DISPLAY INVISIBLE (-6475 -1250);
FORCEPROP 0 LAST $SEC 1
J 0
(-6475 -1250);
DISPLAY 0.680851 (-6475 -1250);
PAINT MONO (-6475 -1250);
DISPLAY INVISIBLE (-6475 -1250);
FORCEPROP 0 LAST CDS_SEC 1
J 0
(-6475 -1250);
DISPLAY 0.680851 (-6475 -1250);
DISPLAY INVISIBLE (-6475 -1250);
FORCEADD OFFPAGE..1
(-7050 -1525);
FORCEPROP 2 LAST $XR1 36 
J 0
(-7271 -1561);
DISPLAY 0.638298 (-7271 -1561);
PAINT MONO (-7271 -1561);
FORCEPROP 2 LAST $XR0 15 
J 0
(-7271 -1525);
DISPLAY 0.638298 (-7271 -1525);
PAINT MONO (-7271 -1525);
FORCEPROP 2 LAST PATH I566
J 0
(-7250 -1475);
DISPLAY 0.680851 (-7250 -1475);
DISPLAY INVISIBLE (-7250 -1475);
FORCEPROP 1 LAST OFFPAGE TRUE
J 0
(-6725 -1650);
DISPLAY 0.872340 (-6725 -1650);
PAINT GREEN (-6725 -1650);
DISPLAY INVISIBLE (-6725 -1650);
FORCEPROP 1 LAST COMMENT_BODY TRUE
J 0
(-6925 -1625);
DISPLAY 0.872340 (-6925 -1625);
PAINT PEACH (-6925 -1625);
DISPLAY INVISIBLE (-6925 -1625);
FORCEPROP 2 LAST CDS_LIB standard
J 0
(-7050 -1525);
DISPLAY INVISIBLE (-7050 -1525);
FORCEADD OFFPAGE..1
(-7050 -1475);
FORCEPROP 2 LAST $XR1 36 
J 0
(-7271 -1439);
DISPLAY 0.638298 (-7271 -1439);
PAINT MONO (-7271 -1439);
FORCEPROP 2 LAST $XR0 15 
J 0
(-7271 -1475);
DISPLAY 0.638298 (-7271 -1475);
PAINT MONO (-7271 -1475);
FORCEPROP 2 LAST PATH I567
J 0
(-7250 -1425);
DISPLAY 0.680851 (-7250 -1425);
DISPLAY INVISIBLE (-7250 -1425);
FORCEPROP 1 LAST OFFPAGE TRUE
J 0
(-6725 -1600);
DISPLAY 0.872340 (-6725 -1600);
PAINT GREEN (-6725 -1600);
DISPLAY INVISIBLE (-6725 -1600);
FORCEPROP 1 LAST COMMENT_BODY TRUE
J 0
(-6925 -1575);
DISPLAY 0.872340 (-6925 -1575);
PAINT PEACH (-6925 -1575);
DISPLAY INVISIBLE (-6925 -1575);
FORCEPROP 2 LAST CDS_LIB standard
J 0
(-7050 -1475);
DISPLAY INVISIBLE (-7050 -1475);
FORCEADD Q_RES..1
R 2
(-6175 -1475);
FORCEPROP 1 LAST MATERIAL CHIP
J 0
(-6000 -1475);
DISPLAY 0.510638 (-6000 -1475);
PAINT SKYBLUE (-6000 -1475);
FORCEPROP 1 LAST VALUE 0
J 2
(-6050 -1475);
DISPLAY 0.510638 (-6050 -1475);
PAINT SKYBLUE (-6050 -1475);
FORCEPROP 1 LAST TOLERANCE 5%
J 2
(-6200 -1500);
DISPLAY 0.510638 (-6200 -1500);
PAINT SKYBLUE (-6200 -1500);
DISPLAY INVISIBLE (-6200 -1500);
FORCEPROP 1 LAST PACK_TYPE 0402LF
J 2
(-6000 -1500);
DISPLAY 0.510638 (-6000 -1500);
PAINT SKYBLUE (-6000 -1500);
DISPLAY INVISIBLE (-6000 -1500);
FORCEPROP 2 LAST CDS_LIB pure_quanta
J 0
(-6175 -1475);
DISPLAY INVISIBLE (-6175 -1475);
FORCEPROP 1 LAST PATH I568
J 2
(-6125 -1325);
DISPLAY 0.978723 (-6125 -1325);
PAINT WHITE (-6125 -1325);
DISPLAY INVISIBLE (-6125 -1325);
FORCEPROP 1 LAST PART_NUMBER CS00002JB13
J 2
(-6225 -1525);
DISPLAY 0.510638 (-6225 -1525);
PAINT WHITE (-6225 -1525);
DISPLAY INVISIBLE (-6225 -1525);
FORCEPROP 1 LAST WATTAGE 1/16W
J 0
(-6425 -1500);
DISPLAY 0.510638 (-6425 -1500);
PAINT SKYBLUE (-6425 -1500);
DISPLAY INVISIBLE (-6425 -1500);
FORCEPROP 1 LAST $LOCATION R838
J 2
(-6275 -1475);
DISPLAY 0.787234 (-6275 -1475);
FORCEPROP 1 LASTPIN (-6075 -1475) $PN 1
J 2
(-6087 -1463);
DISPLAY 0.787234 (-6087 -1463);
PAINT MONO (-6087 -1463);
FORCEPROP 1 LASTPIN (-6275 -1475) $PN 2
J 2
(-6237 -1463);
DISPLAY 0.787234 (-6237 -1463);
PAINT MONO (-6237 -1463);
FORCEPROP 0 LAST CDS_LOCATION R838
J 0
(-6125 -1375);
DISPLAY 0.680851 (-6125 -1375);
DISPLAY INVISIBLE (-6125 -1375);
FORCEPROP 0 LAST $SEC 1
J 0
(-6125 -1375);
DISPLAY 0.680851 (-6125 -1375);
PAINT MONO (-6125 -1375);
DISPLAY INVISIBLE (-6125 -1375);
FORCEPROP 0 LAST CDS_SEC 1
J 0
(-6125 -1375);
DISPLAY 0.680851 (-6125 -1375);
DISPLAY INVISIBLE (-6125 -1375);
FORCEADD Q_RES..1
R 2
(-6175 -1525);
FORCEPROP 1 LAST VALUE 0
J 2
(-6050 -1525);
DISPLAY 0.510638 (-6050 -1525);
PAINT SKYBLUE (-6050 -1525);
FORCEPROP 1 LAST MATERIAL CHIP
J 0
(-6000 -1525);
DISPLAY 0.510638 (-6000 -1525);
PAINT SKYBLUE (-6000 -1525);
FORCEPROP 2 LAST CDS_LIB pure_quanta
J 0
(-6175 -1525);
DISPLAY INVISIBLE (-6175 -1525);
FORCEPROP 1 LAST PATH I569
J 2
(-6125 -1375);
DISPLAY 0.978723 (-6125 -1375);
PAINT WHITE (-6125 -1375);
DISPLAY INVISIBLE (-6125 -1375);
FORCEPROP 1 LAST PART_NUMBER CS00002JB13
J 2
(-6225 -1575);
DISPLAY 0.510638 (-6225 -1575);
PAINT WHITE (-6225 -1575);
DISPLAY INVISIBLE (-6225 -1575);
FORCEPROP 1 LAST WATTAGE 1/16W
J 0
(-6425 -1550);
DISPLAY 0.510638 (-6425 -1550);
PAINT SKYBLUE (-6425 -1550);
DISPLAY INVISIBLE (-6425 -1550);
FORCEPROP 1 LAST TOLERANCE 5%
J 2
(-6200 -1550);
DISPLAY 0.510638 (-6200 -1550);
PAINT SKYBLUE (-6200 -1550);
DISPLAY INVISIBLE (-6200 -1550);
FORCEPROP 1 LAST PACK_TYPE 0402LF
J 2
(-6000 -1550);
DISPLAY 0.510638 (-6000 -1550);
PAINT SKYBLUE (-6000 -1550);
DISPLAY INVISIBLE (-6000 -1550);
FORCEPROP 1 LAST $LOCATION R847
J 2
(-6275 -1525);
DISPLAY 0.787234 (-6275 -1525);
FORCEPROP 1 LASTPIN (-6075 -1525) $PN 1
J 2
(-6087 -1513);
DISPLAY 0.787234 (-6087 -1513);
PAINT MONO (-6087 -1513);
FORCEPROP 1 LASTPIN (-6275 -1525) $PN 2
J 2
(-6237 -1513);
DISPLAY 0.787234 (-6237 -1513);
PAINT MONO (-6237 -1513);
FORCEPROP 0 LAST CDS_LOCATION R847
J 0
(-6125 -1425);
DISPLAY 0.680851 (-6125 -1425);
DISPLAY INVISIBLE (-6125 -1425);
FORCEPROP 0 LAST $SEC 1
J 0
(-6125 -1425);
DISPLAY 0.680851 (-6125 -1425);
PAINT MONO (-6125 -1425);
DISPLAY INVISIBLE (-6125 -1425);
FORCEPROP 0 LAST CDS_SEC 1
J 0
(-6125 -1425);
DISPLAY 0.680851 (-6125 -1425);
DISPLAY INVISIBLE (-6125 -1425);
FORCEADD OFFPAGE..4
(-5925 2300);
FORCEPROP 2 LAST $XR2 36 
J 0
(-5529 2300);
DISPLAY 0.638298 (-5529 2300);
PAINT MONO (-5529 2300);
FORCEPROP 2 LAST $XR1 15 
J 0
(-5619 2300);
DISPLAY 0.638298 (-5619 2300);
PAINT MONO (-5619 2300);
FORCEPROP 2 LAST $XR0 28 
J 0
(-5709 2300);
DISPLAY 0.638298 (-5709 2300);
PAINT MONO (-5709 2300);
FORCEPROP 1 LAST COMMENT_BODY TRUE
J 0
(-5950 2200);
DISPLAY 0.872340 (-5950 2200);
PAINT PEACH (-5950 2200);
DISPLAY INVISIBLE (-5950 2200);
FORCEPROP 1 LAST OFFPAGE TRUE
J 0
(-5600 2175);
DISPLAY 0.872340 (-5600 2175);
PAINT GREEN (-5600 2175);
DISPLAY INVISIBLE (-5600 2175);
FORCEPROP 2 LAST CDS_LIB standard
J 0
(-5925 2300);
DISPLAY INVISIBLE (-5925 2300);
FORCEPROP 2 LAST PATH I570
J 0
(-5550 2350);
DISPLAY 0.680851 (-5550 2350);
DISPLAY INVISIBLE (-5550 2350);
FORCEADD OFFPAGE..5
(-11175 -450);
FORCEPROP 2 LAST $XR0 36 
J 0
(-11429 -450);
DISPLAY 0.638298 (-11429 -450);
PAINT MONO (-11429 -450);
FORCEPROP 2 LAST PATH I571
J 0
(-11375 -400);
DISPLAY 0.680851 (-11375 -400);
DISPLAY INVISIBLE (-11375 -400);
FORCEPROP 2 LAST CDS_LIB standard
J 0
(-11175 -450);
DISPLAY INVISIBLE (-11175 -450);
FORCEPROP 1 LAST COMMENT_BODY TRUE
J 0
(-11075 -525);
DISPLAY 0.872340 (-11075 -525);
PAINT PEACH (-11075 -525);
DISPLAY INVISIBLE (-11075 -525);
FORCEPROP 1 LAST OFFPAGE TRUE
J 0
(-10850 -575);
DISPLAY 0.872340 (-10850 -575);
PAINT GREEN (-10850 -575);
DISPLAY INVISIBLE (-10850 -575);
FORCEADD OFFPAGE..5
(-11175 -600);
FORCEPROP 2 LAST $XR0 36 
J 0
(-11429 -600);
DISPLAY 0.638298 (-11429 -600);
PAINT MONO (-11429 -600);
FORCEPROP 2 LAST PATH I572
J 0
(-11375 -550);
DISPLAY 0.680851 (-11375 -550);
DISPLAY INVISIBLE (-11375 -550);
FORCEPROP 2 LAST CDS_LIB standard
J 0
(-11175 -600);
DISPLAY INVISIBLE (-11175 -600);
FORCEPROP 1 LAST COMMENT_BODY TRUE
J 0
(-11075 -675);
DISPLAY 0.872340 (-11075 -675);
PAINT PEACH (-11075 -675);
DISPLAY INVISIBLE (-11075 -675);
FORCEPROP 1 LAST OFFPAGE TRUE
J 0
(-10850 -725);
DISPLAY 0.872340 (-10850 -725);
PAINT GREEN (-10850 -725);
DISPLAY INVISIBLE (-10850 -725);
FORCEADD Q_CAP..1
(-10225 3375);
FORCEPROP 1 LAST TOLERANCE 20%
J 0
(-10175 3325);
DISPLAY 0.510638 (-10175 3325);
PAINT SKYBLUE (-10175 3325);
FORCEPROP 1 LAST MATERIAL X6S
J 0
(-10175 3275);
DISPLAY 0.510638 (-10175 3275);
PAINT SKYBLUE (-10175 3275);
FORCEPROP 1 LAST PART_NUMBER CH6223MEA01
J 0
(-10175 3225);
DISPLAY 0.510638 (-10175 3225);
PAINT WHITE (-10175 3225);
FORCEPROP 1 LAST PACK_TYPE C0805
J 0
(-10175 3175);
DISPLAY 0.510638 (-10175 3175);
PAINT SKYBLUE (-10175 3175);
FORCEPROP 1 LAST VALUE 22UF
J 0
(-10175 3425);
DISPLAY 0.510638 (-10175 3425);
PAINT SKYBLUE (-10175 3425);
FORCEPROP 1 LAST VOLTAGE 16V
J 0
(-10175 3375);
DISPLAY 0.510638 (-10175 3375);
PAINT SKYBLUE (-10175 3375);
FORCEPROP 1 LAST PATH I573
J 0
(-10175 3525);
DISPLAY 0.978723 (-10175 3525);
PAINT WHITE (-10175 3525);
DISPLAY INVISIBLE (-10175 3525);
FORCEPROP 2 LAST CDS_LIB pure_quanta
J 0
(-10225 3375);
DISPLAY INVISIBLE (-10225 3375);
FORCEPROP 1 LAST LOCATION C329
J 0
(-10175 3475);
DISPLAY 0.702128 (-10175 3475);
PAINT AQUA (-10175 3475);
FORCEPROP 1 LASTPIN (-10225 3475) $PN 1
J 0
(-10215 3455);
DISPLAY 0.787234 (-10215 3455);
PAINT MONO (-10215 3455);
FORCEPROP 1 LASTPIN (-10225 3275) $PN 2
J 0
(-10215 3255);
DISPLAY 0.787234 (-10215 3255);
PAINT MONO (-10215 3255);
FORCEPROP 0 LAST $SEC 1
J 0
(-10175 3525);
DISPLAY 0.680851 (-10175 3525);
PAINT MONO (-10175 3525);
DISPLAY INVISIBLE (-10175 3525);
FORCEPROP 0 LAST CDS_SEC 1
J 0
(-10175 3525);
DISPLAY 0.680851 (-10175 3525);
DISPLAY INVISIBLE (-10175 3525);
FORCEADD Q_CAP..1
(-9800 3375);
FORCEPROP 1 LAST PART_NUMBER CH6223MEA01
J 0
(-9750 3225);
DISPLAY 0.510638 (-9750 3225);
PAINT WHITE (-9750 3225);
FORCEPROP 1 LAST VOLTAGE 16V
J 0
(-9750 3375);
DISPLAY 0.510638 (-9750 3375);
PAINT SKYBLUE (-9750 3375);
FORCEPROP 1 LAST PACK_TYPE C0805
J 0
(-9750 3175);
DISPLAY 0.510638 (-9750 3175);
PAINT SKYBLUE (-9750 3175);
FORCEPROP 1 LAST TOLERANCE 20%
J 0
(-9750 3325);
DISPLAY 0.510638 (-9750 3325);
PAINT SKYBLUE (-9750 3325);
FORCEPROP 1 LAST MATERIAL X6S
J 0
(-9750 3275);
DISPLAY 0.510638 (-9750 3275);
PAINT SKYBLUE (-9750 3275);
FORCEPROP 1 LAST VALUE 22UF
J 0
(-9750 3425);
DISPLAY 0.510638 (-9750 3425);
PAINT SKYBLUE (-9750 3425);
FORCEPROP 1 LAST PATH I574
J 0
(-9750 3525);
DISPLAY 0.978723 (-9750 3525);
PAINT WHITE (-9750 3525);
DISPLAY INVISIBLE (-9750 3525);
FORCEPROP 2 LAST CDS_LIB pure_quanta
J 0
(-9800 3375);
DISPLAY INVISIBLE (-9800 3375);
FORCEPROP 1 LAST LOCATION C330
J 0
(-9750 3475);
DISPLAY 0.702128 (-9750 3475);
PAINT AQUA (-9750 3475);
FORCEPROP 1 LASTPIN (-9800 3475) $PN 1
J 0
(-9790 3455);
DISPLAY 0.787234 (-9790 3455);
PAINT MONO (-9790 3455);
FORCEPROP 1 LASTPIN (-9800 3275) $PN 2
J 0
(-9790 3255);
DISPLAY 0.787234 (-9790 3255);
PAINT MONO (-9790 3255);
FORCEPROP 0 LAST $SEC 1
J 0
(-9750 3525);
DISPLAY 0.680851 (-9750 3525);
PAINT MONO (-9750 3525);
DISPLAY INVISIBLE (-9750 3525);
FORCEPROP 0 LAST CDS_SEC 1
J 0
(-9750 3525);
DISPLAY 0.680851 (-9750 3525);
DISPLAY INVISIBLE (-9750 3525);
FORCEADD OFFPAGE..6
(-11175 -550);
FORCEPROP 2 LAST $XR0 12 
J 0
(-11424 -550);
DISPLAY 0.638298 (-11424 -550);
PAINT MONO (-11424 -550);
FORCEPROP 2 LAST PATH I575
J 0
(-11400 -500);
DISPLAY 0.680851 (-11400 -500);
DISPLAY INVISIBLE (-11400 -500);
FORCEPROP 2 LAST CDS_LIB standard
J 0
(-11175 -550);
DISPLAY INVISIBLE (-11175 -550);
FORCEPROP 1 LAST OFFPAGE TRUE
J 0
(-10850 -675);
DISPLAY 0.872340 (-10850 -675);
PAINT GREEN (-10850 -675);
DISPLAY INVISIBLE (-10850 -675);
FORCEPROP 1 LAST COMMENT_BODY TRUE
J 0
(-11075 -625);
DISPLAY 0.872340 (-11075 -625);
PAINT PEACH (-11075 -625);
DISPLAY INVISIBLE (-11075 -625);
FORCEADD OFFPAGE..2
(-5925 2450);
FORCEPROP 2 LAST CDS_LIB standard
J 0
(-5925 2450);
DISPLAY INVISIBLE (-5925 2450);
FORCEPROP 1 LAST COMMENT_BODY TRUE
J 0
(-5970 2355);
DISPLAY 0.872340 (-5970 2355);
PAINT PEACH (-5970 2355);
DISPLAY INVISIBLE (-5970 2355);
FORCEPROP 1 LAST OFFPAGE TRUE
J 0
(-5600 2325);
DISPLAY 0.872340 (-5600 2325);
PAINT GREEN (-5600 2325);
DISPLAY INVISIBLE (-5600 2325);
FORCEPROP 2 LAST PATH I576
J 0
(-5750 2525);
DISPLAY 0.680851 (-5750 2525);
DISPLAY INVISIBLE (-5750 2525);
FORCEADD OFFPAGE..2
(-5925 2350);
FORCEPROP 2 LAST $XR0 13 
J 0
(-5736 2350);
DISPLAY 0.638298 (-5736 2350);
PAINT MONO (-5736 2350);
FORCEPROP 1 LAST OFFPAGE TRUE
J 0
(-5600 2225);
DISPLAY 0.872340 (-5600 2225);
PAINT GREEN (-5600 2225);
DISPLAY INVISIBLE (-5600 2225);
FORCEPROP 1 LAST COMMENT_BODY TRUE
J 0
(-5970 2255);
DISPLAY 0.872340 (-5970 2255);
PAINT PEACH (-5970 2255);
DISPLAY INVISIBLE (-5970 2255);
FORCEPROP 2 LAST CDS_LIB standard
J 0
(-5925 2350);
DISPLAY INVISIBLE (-5925 2350);
FORCEPROP 2 LAST PATH I577
J 0
(-5750 2425);
DISPLAY 0.680851 (-5750 2425);
DISPLAY INVISIBLE (-5750 2425);
FORCEADD OFFPAGE..2
(-5925 2550);
FORCEPROP 2 LAST $XR0 31 
J 0
(-5736 2550);
DISPLAY 0.638298 (-5736 2550);
PAINT MONO (-5736 2550);
FORCEPROP 1 LAST COMMENT_BODY TRUE
J 0
(-5970 2455);
DISPLAY 0.872340 (-5970 2455);
PAINT PEACH (-5970 2455);
DISPLAY INVISIBLE (-5970 2455);
FORCEPROP 1 LAST OFFPAGE TRUE
J 0
(-5600 2425);
DISPLAY 0.872340 (-5600 2425);
PAINT GREEN (-5600 2425);
DISPLAY INVISIBLE (-5600 2425);
FORCEPROP 2 LAST PATH I578
J 0
(-5750 2625);
DISPLAY 0.680851 (-5750 2625);
DISPLAY INVISIBLE (-5750 2625);
FORCEPROP 2 LAST CDS_LIB standard
J 0
(-5925 2550);
DISPLAY INVISIBLE (-5925 2550);
FORCEADD OFFPAGE..2
(-5925 100);
FORCEPROP 2 LAST $XR0 13 
J 0
(-5736 100);
DISPLAY 0.638298 (-5736 100);
PAINT MONO (-5736 100);
FORCEPROP 1 LAST COMMENT_BODY TRUE
J 0
(-5970 5);
DISPLAY 0.872340 (-5970 5);
PAINT PEACH (-5970 5);
DISPLAY INVISIBLE (-5970 5);
FORCEPROP 1 LAST OFFPAGE TRUE
J 0
(-5600 -25);
DISPLAY 0.872340 (-5600 -25);
PAINT GREEN (-5600 -25);
DISPLAY INVISIBLE (-5600 -25);
FORCEPROP 2 LAST CDS_LIB standard
J 0
(-5925 100);
DISPLAY INVISIBLE (-5925 100);
FORCEPROP 2 LAST PATH I579
J 0
(-5725 150);
DISPLAY 0.680851 (-5725 150);
DISPLAY INVISIBLE (-5725 150);
FORCEADD QUANTA_TITLE_BLOCK_C..1
(-3775 -2400);
FORCEPROP 0 LAST CDS_CON_LAST_MODIFIED Fri Aug 25 17:25:35 2023
J 0
(-5660 -2385);
DISPLAY INVISIBLE (-5660 -2385);
FORCEPROP 2 LAST Q_DEPT 
J 1
(-7538 -2351);
DISPLAY 1.957447 (-7538 -2351);
PAINT GREEN (-7538 -2351);
FORCEPROP 1 LAST CUSTOM_TXT_CDS <CON_LAST_MODIFIED>
J 0
(-5660 -2385);
DISPLAY 0.978723 (-5660 -2385);
FORCEPROP 2 LAST CUSTOM_TXT_CDS <XR_PAGE_TITLE>
J 0
(-11665 2850);
DISPLAY 0.638298 (-11665 2850);
PAINT PINK (-11665 2850);
DISPLAY INVISIBLE (-11665 2850);
FORCEPROP 1 LAST CUSTOM_TXT_CDS <NAME_2>
J 0
(-6950 -2350);
FORCEPROP 1 LAST CUSTOM_TXT_CDS <NAME_1>
J 0
(-6950 -2225);
FORCEPROP 1 LAST CUSTOM_TXT_CDS <Q_NUMBER>
J 0
(-5178 -2297);
DISPLAY 1.212766 (-5178 -2297);
FORCEPROP 1 LAST CUSTOM_TXT_CDS <Q_PROJ>
J 0
(-6157 -2298);
DISPLAY 1.212766 (-6157 -2298);
FORCEPROP 1 LAST CUSTOM_TXT_CDS <Q_REV>
J 0
(-3959 -2297);
DISPLAY 1.212766 (-3959 -2297);
FORCEPROP 1 LAST CUSTOM_TXT_CDS <CON_PAGE_NUM> OF <CON_TOTAL_PAGES>
J 0
(-4221 -2382);
DISPLAY 0.978723 (-4221 -2382);
FORCEPROP 1 LAST Q_TITLE OCP 3.0 SCM FINGER 1/2
J 0
(-13141 -2374);
DISPLAY 2.446809 (-13141 -2374);
PAINT GREEN (-13141 -2374);
FORCEPROP 2 LAST CDS_XR_PAGE_TITLE CR-10 : @SCM_LIB.SCM(SCH_1):PAGE10
J 0
(-11665 2850);
DISPLAY 0.638298 (-11665 2850);
PAINT PINK (-11665 2850);
DISPLAY INVISIBLE (-11665 2850);
FORCEPROP 2 LAST CDS_LIB pure_quanta
J 0
(-3775 -2400);
DISPLAY INVISIBLE (-3775 -2400);
FORCEPROP 1 LAST CDS_LMAN_SYM_OUTLINE -9475,6775,100,-125
J 0
(-3775 -2400);
DISPLAY 0.468085 (-3775 -2400);
PAINT GREEN (-3775 -2400);
DISPLAY INVISIBLE (-3775 -2400);
FORCEPROP 2 LAST PAGE_BORDER TRUE
J 0
(-11665 2850);
DISPLAY 0.638298 (-11665 2850);
PAINT PINK (-11665 2850);
DISPLAY INVISIBLE (-11665 2850);
FORCEPROP 1 LAST COMMENT_BODY TRUE
J 0
(-3763 -2413);
DISPLAY 0.978723 (-3763 -2413);
PAINT PEACH (-3763 -2413);
DISPLAY INVISIBLE (-3763 -2413);
FORCEADD DNS..2
(-4675 -75);
PAINT RED (-4675 -75);
FORCEPROP 1 LAST COMMENT_BODY TRUE
R 1
J 0
(-4600 -300);
DISPLAY 0.872340 (-4600 -300);
PAINT PEACH (-4600 -300);
DISPLAY INVISIBLE (-4600 -300);
FORCEPROP 2 LAST CDS_LIB mstr_misc
J 0
(-4675 -75);
DISPLAY INVISIBLE (-4675 -75);
FORCEADD DNS..2
(-6425 -1275);
PAINT RED (-6425 -1275);
FORCEPROP 2 LAST CDS_LIB mstr_misc
J 0
(-6425 -1275);
DISPLAY INVISIBLE (-6425 -1275);
FORCEPROP 1 LAST COMMENT_BODY TRUE
R 1
J 0
(-6350 -1500);
DISPLAY 0.872340 (-6350 -1500);
PAINT PEACH (-6350 -1500);
DISPLAY INVISIBLE (-6350 -1500);
FORCEADD DESIGN_NOTE..1
(-6075 -1775);
FORCEPROP 0 LAST L1 COLAY SGPIO AND REAL PIN
J 0
(-6200 -1900);
DISPLAY 1.021277 (-6200 -1900);
PAINT WHITE (-6200 -1900);
FORCEPROP 1 LAST COMMENT_BODY TRUE
J 0
(-6050 -1675);
DISPLAY 0.978723 (-6050 -1675);
PAINT PEACH (-6050 -1675);
DISPLAY INVISIBLE (-6050 -1675);
FORCEPROP 2 LAST CDS_LIB logical_power
J 0
(-6075 -1775);
DISPLAY INVISIBLE (-6075 -1775);
FORCEADD DESIGN_NOTE..1
(-5200 475);
FORCEPROP 0 LAST L2 
J 0
(-5325 250);
DISPLAY 1.021277 (-5325 250);
PAINT WHITE (-5325 250);
FORCEPROP 0 LAST L1 0.1UF SHOULD CLOSED GF1 P3V_BAT_R
J 0
(-5425 350);
DISPLAY 1.021277 (-5425 350);
PAINT WHITE (-5425 350);
FORCEPROP 1 LAST COMMENT_BODY TRUE
J 0
(-5175 575);
DISPLAY 0.978723 (-5175 575);
PAINT PEACH (-5175 575);
DISPLAY INVISIBLE (-5175 575);
FORCEPROP 2 LAST CDS_LIB logical_power
J 0
(-5200 475);
DISPLAY INVISIBLE (-5200 475);
FORCEADD DESIGN_NOTE..1
(-5375 -175);
FORCEPROP 0 LAST L1 QSPI_2_*
J 0
(-5500 -300);
DISPLAY 1.021277 (-5500 -300);
PAINT WHITE (-5500 -300);
FORCEPROP 0 LAST L2 RESERVED FOR UPDATE BMC
J 0
(-5500 -400);
DISPLAY 1.021277 (-5500 -400);
PAINT WHITE (-5500 -400);
FORCEPROP 1 LAST COMMENT_BODY TRUE
J 0
(-5350 -75);
DISPLAY 0.978723 (-5350 -75);
PAINT PEACH (-5350 -75);
DISPLAY INVISIBLE (-5350 -75);
FORCEPROP 2 LAST CDS_LIB logical_power
J 0
(-5375 -175);
DISPLAY INVISIBLE (-5375 -175);
FORCEADD DESIGN_NOTE..1
(-5200 1675);
FORCEPROP 0 LAST L1 SPI_SYS_* FROM PCH
J 0
(-5250 1550);
DISPLAY 1.021277 (-5250 1550);
PAINT WHITE (-5250 1550);
FORCEPROP 1 LAST COMMENT_BODY TRUE
J 0
(-5175 1775);
DISPLAY 0.978723 (-5175 1775);
PAINT PEACH (-5175 1775);
DISPLAY INVISIBLE (-5175 1775);
FORCEPROP 2 LAST CDS_LIB logical_power
J 0
(-5200 1675);
DISPLAY INVISIBLE (-5200 1675);
FORCEADD DESIGN_NOTE..1
(-5300 2450);
FORCEPROP 0 LAST L1 RESERVED SPI_TPM* FROM CPU TO TPM
J 0
(-5450 2325);
DISPLAY 1.021277 (-5450 2325);
PAINT WHITE (-5450 2325);
FORCEPROP 2 LAST CDS_LIB logical_power
J 0
(-5300 2450);
DISPLAY INVISIBLE (-5300 2450);
FORCEPROP 1 LAST COMMENT_BODY TRUE
J 0
(-5275 2550);
DISPLAY 0.978723 (-5275 2550);
PAINT PEACH (-5275 2550);
DISPLAY INVISIBLE (-5275 2550);
WIRE 16 -1 (-10225 3575)(-10225 3675);
WIRE 16 -1 (-10225 3575)(-9800 3575);
WIRE 16 -1 (-10225 3575)(-10225 3475);
WIRE 16 -1 (-7300 3150)(-7300 2950);
WIRE 16 -1 (-9300 -1650)(-9300 -1350);
WIRE 16 -1 (-10225 3050)(-10225 3100);
WIRE 16 -1 (-7300 -1650)(-7300 -1350);
WIRE 16 -1 (-4675 -150)(-4675 -250);
WIRE 16 -1 (-7500 2950)(-7300 2950);
WIRE 16 -1 (-7300 2950)(-7300 2900);
WIRE 16 -1 (-7500 2900)(-7300 2900);
WIRE 16 -1 (-9300 -1350)(-9050 -1350);
WIRE 16 -1 (-9300 -1350)(-9300 -1200);
WIRE 16 -1 (-9300 -1200)(-9050 -1200);
WIRE 16 -1 (-9300 -1200)(-9300 -1050);
WIRE 16 -1 (-9300 -1050)(-9050 -1050);
WIRE 16 -1 (-9300 -1050)(-9300 -900);
WIRE 16 -1 (-9300 -900)(-9050 -900);
WIRE 16 -1 (-9300 -900)(-9300 -750);
WIRE 16 -1 (-9300 -750)(-9050 -750);
WIRE 16 -1 (-9300 100)(-9300 -750);
WIRE 16 -1 (-9300 100)(-9050 100);
WIRE 16 -1 (-9300 100)(-9300 550);
WIRE 16 -1 (-9050 550)(-9300 550);
WIRE 16 -1 (-9300 550)(-9300 1150);
WIRE 16 -1 (-9050 1150)(-9300 1150);
WIRE 16 -1 (-9300 1150)(-9300 1300);
WIRE 16 -1 (-9050 1300)(-9300 1300);
WIRE 16 -1 (-9300 1300)(-9300 1450);
WIRE 16 -1 (-9050 1450)(-9300 1450);
WIRE 16 -1 (-9300 1450)(-9300 1600);
WIRE 16 -1 (-9050 1600)(-9300 1600);
WIRE 16 -1 (-9300 1600)(-9300 2350);
WIRE 16 -1 (-9300 2350)(-9050 2350);
WIRE 16 -1 (-9300 2350)(-9300 2800);
WIRE 16 -1 (-9050 2800)(-9300 2800);
WIRE 16 -1 (-9300 2850)(-9300 2800);
WIRE 16 -1 (-9050 2850)(-9300 2850);
WIRE 16 -1 (-7500 -1350)(-7300 -1350);
WIRE 16 -1 (-7300 -1350)(-7300 -1200);
WIRE 16 -1 (-7500 -1200)(-7300 -1200);
WIRE 16 -1 (-7300 -1050)(-7300 -1200);
WIRE 16 -1 (-7500 -1050)(-7300 -1050);
WIRE 16 -1 (-7300 -900)(-7300 -1050);
WIRE 16 -1 (-7300 -900)(-7500 -900);
WIRE 16 -1 (-7300 -750)(-7500 -750);
WIRE 16 -1 (-7300 -750)(-7300 -900);
WIRE 16 -1 (-7300 -600)(-7500 -600);
WIRE 16 -1 (-7300 -600)(-7300 -750);
WIRE 16 -1 (-7300 -450)(-7300 -600);
WIRE 16 -1 (-7300 -450)(-7500 -450);
WIRE 16 -1 (-7300 -300)(-7500 -300);
WIRE 16 -1 (-7300 -300)(-7300 -450);
WIRE 16 -1 (-7300 300)(-7300 -300);
WIRE 16 -1 (-7300 300)(-7500 300);
WIRE 16 -1 (-7300 300)(-7300 550);
WIRE 16 -1 (-7300 550)(-7500 550);
WIRE 16 -1 (-7300 950)(-7500 950);
WIRE 16 -1 (-7300 550)(-7300 950);
WIRE 16 -1 (-7300 950)(-7300 1400);
WIRE 16 -1 (-7300 1400)(-7500 1400);
WIRE 16 -1 (-7300 1400)(-7300 1750);
WIRE 16 -1 (-7300 1750)(-7500 1750);
WIRE 16 -1 (-7300 1750)(-7300 2500);
WIRE 16 -1 (-7500 2500)(-7300 2500);
WIRE 16 -1 (-7300 2500)(-7300 2650);
WIRE 16 -1 (-7500 2650)(-7300 2650);
WIRE 16 -1 (-7300 2650)(-7300 2800);
WIRE 16 -1 (-7500 2800)(-7300 2800);
WIRE 16 -1 (-7500 -1150)(-5975 -1150);
FORCEPROP 2 LAST SIG_NAME P2E_GPU_TX_C_DN
J 0
(-6585 -1140);
DISPLAY 0.851064 (-6585 -1140);
WIRE 16 -1 (-7500 -1100)(-5975 -1100);
FORCEPROP 2 LAST SIG_NAME P2E_GPU_TX_C_DP
J 0
(-6585 -1090);
DISPLAY 0.851064 (-6585 -1090);
WIRE 16 -1 (-5975 -850)(-7500 -850);
FORCEPROP 2 LAST SIG_NAME USB3_FPNL_TXN
J 2
(-5960 -840);
DISPLAY 0.808511 (-5960 -840);
WIRE 16 3135 (-6425 -1625)(-5875 -1625);
WIRE 16 3135 (-6425 -1375)(-6425 -1625);
WIRE 16 3135 (-5875 -1375)(-5875 -1625);
WIRE 16 3135 (-5875 -1375)(-6425 -1375);
WIRE 16 -1 (-6350 -1300)(-5625 -1300);
FORCEPROP 2 LAST SIG_NAME PCH_BEEP_LED
J 0
(-6160 -1290);
DISPLAY 0.851064 (-6160 -1290);
WIRE 16 -1 (-5625 -1300)(-5525 -1300);
WIRE 16 -1 (-5625 -1525)(-5625 -1300);
WIRE 16 -1 (-6075 -1525)(-5625 -1525);
WIRE 16 -1 (-6350 -1250)(-5675 -1250);
FORCEPROP 2 LAST SIG_NAME HDD_LED_N
J 0
(-6060 -1240);
DISPLAY 0.851064 (-6060 -1240);
WIRE 16 -1 (-5525 -1250)(-5675 -1250);
WIRE 16 -1 (-5675 -1475)(-5675 -1250);
WIRE 16 -1 (-6075 -1475)(-5675 -1475);
WIRE 16 -1 (-5975 -800)(-7500 -800);
FORCEPROP 2 LAST SIG_NAME USB3_FPNL_TXP
J 2
(-5960 -790);
DISPLAY 0.808511 (-5960 -790);
WIRE 16 -1 (-5975 -200)(-7500 -200);
FORCEPROP 2 LAST SIG_NAME QSPI_2_PLD_IO2
J 2
(-5950 -190);
DISPLAY 0.808511 (-5950 -190);
WIRE 16 -1 (-7500 -700)(-5975 -700);
FORCEPROP 2 LAST SIG_NAME USB_FPNL_DN
J 2
(-5960 -690);
DISPLAY 0.808511 (-5960 -690);
WIRE 16 -1 (-5975 -500)(-7500 -500);
FORCEPROP 2 LAST SIG_NAME USB_HOST_BMC_A_DP
J 2
(-5950 -490);
DISPLAY 0.808511 (-5950 -490);
WIRE 16 -1 (-5975 -50)(-7500 -50);
FORCEPROP 2 LAST SIG_NAME TP_GF1_B44
J 2
(-5950 -40);
DISPLAY 0.808511 (-5950 -40);
WIRE 16 -1 (-5975 200)(-7500 200);
FORCEPROP 2 LAST SIG_NAME IRQ_SGPIO_N
J 2
(-5950 210);
DISPLAY 0.808511 (-5950 210);
WIRE 16 -1 (-5975 450)(-7500 450);
FORCEPROP 2 LAST SIG_NAME SGPIO_CLK_1
J 2
(-5950 460);
DISPLAY 0.808511 (-5950 460);
WIRE 16 -1 (-5975 600)(-7500 600);
FORCEPROP 2 LAST SIG_NAME SGPIO_LD_0
J 2
(-5950 610);
DISPLAY 0.808511 (-5950 610);
WIRE 16 -1 (-7500 700)(-5975 700);
FORCEPROP 2 LAST SIG_NAME SGPIO_CLK_0
J 2
(-5950 710);
DISPLAY 0.808511 (-5950 710);
WIRE 16 -1 (-5975 750)(-7500 750);
FORCEPROP 2 LAST SIG_NAME SGPIO_DO_0
J 2
(-5950 760);
DISPLAY 0.808511 (-5950 760);
WIRE 16 -1 (-5975 650)(-7500 650);
FORCEPROP 2 LAST SIG_NAME SGPIO_DI_0
J 2
(-5950 660);
DISPLAY 0.808511 (-5950 660);
WIRE 16 -1 (-5975 500)(-7500 500);
FORCEPROP 2 LAST SIG_NAME SGPIO_DO_1
J 2
(-5950 510);
DISPLAY 0.808511 (-5950 510);
WIRE 16 -1 (-5975 400)(-7500 400);
FORCEPROP 2 LAST SIG_NAME SGPIO_DI_1
J 2
(-5950 410);
DISPLAY 0.808511 (-5950 410);
WIRE 16 -1 (-4675 50)(-4675 150);
WIRE 16 -1 (-4550 150)(-4675 150);
WIRE 16 -1 (-7500 150)(-4675 150);
FORCEPROP 2 LAST SIG_NAME P3V_BAT_R
J 0
(-4935 160);
DISPLAY 0.851064 (-4935 160);
WIRE 16 -1 (-5975 1300)(-7500 1300);
FORCEPROP 2 LAST SIG_NAME RMII_CSRDV
J 2
(-5950 1310);
DISPLAY 0.808511 (-5950 1310);
WIRE 16 -1 (-5975 1350)(-7500 1350);
FORCEPROP 2 LAST SIG_NAME RMII_OCP_RCLKI
J 2
(-5950 1360);
DISPLAY 0.808511 (-5950 1360);
WIRE 16 -1 (-7500 1450)(-5975 1450);
FORCEPROP 2 LAST SIG_NAME SPI_SYS_HOLD_R_IO3
J 2
(-5950 1460);
DISPLAY 0.808511 (-5950 1460);
WIRE 16 -1 (-7500 1500)(-5975 1500);
FORCEPROP 2 LAST SIG_NAME SPI_SYS_WP_R_IO2
J 2
(-5950 1510);
DISPLAY 0.808511 (-5950 1510);
WIRE 16 -1 (-9050 1800)(-11125 1800);
FORCEPROP 2 LAST SIG_NAME SMB_BMC_MM4_SCL
J 0
(-11125 1810);
DISPLAY 0.808511 (-11125 1810);
WIRE 16 -1 (-9050 1850)(-11125 1850);
FORCEPROP 2 LAST SIG_NAME SMB_BMC_MM3_SDA
J 0
(-11125 1860);
DISPLAY 0.808511 (-11125 1860);
WIRE 16 -1 (-9050 1900)(-11125 1900);
FORCEPROP 2 LAST SIG_NAME SMB_BMC_MM3_SCL
J 0
(-11125 1910);
DISPLAY 0.808511 (-11125 1910);
WIRE 16 -1 (-9800 3575)(-9800 3475);
WIRE 16 -1 (-9800 3575)(-9300 3575);
WIRE 16 -1 (-9300 3575)(-9300 2950);
WIRE 16 -1 (-9050 2950)(-9300 2950);
WIRE 16 -1 (-9300 2950)(-9300 2900);
WIRE 16 -1 (-9050 2900)(-9300 2900);
WIRE 16 -1 (-9800 3275)(-9800 3100);
WIRE 16 -1 (-10225 3100)(-10225 3275);
WIRE 16 -1 (-9800 3100)(-10225 3100);
WIRE 16 -1 (-6525 -950)(-7500 -950);
FORCEPROP 2 LAST SIG_NAME TP_GF_B62
J 0
(-6885 -940);
DISPLAY 0.808511 (-6885 -940);
WIRE 16 -1 (-6525 -1000)(-7500 -1000);
FORCEPROP 2 LAST SIG_NAME TP_GF_B63
J 0
(-6885 -990);
DISPLAY 0.808511 (-6885 -990);
WIRE 16 -1 (-7500 -1250)(-6550 -1250);
FORCEPROP 2 LAST SIG_NAME HDD_LED_R_N
J 0
(-7260 -1240);
DISPLAY 0.851064 (-7260 -1240);
WIRE 16 -1 (-6275 -1525)(-7000 -1525);
FORCEPROP 2 LAST SIG_NAME FM_PCH_BEEP_LED
J 2
(-6435 -1515);
DISPLAY 0.808511 (-6435 -1515);
WIRE 16 -1 (-7500 2850)(-6525 2850);
FORCEPROP 2 LAST SIG_NAME FM_PRSNT_0_R_N
J 0
(-7185 2860);
DISPLAY 0.808511 (-7185 2860);
WIRE 16 -1 (-7500 2750)(-5975 2750);
FORCEPROP 2 LAST SIG_NAME UART_BIC_GF_TXD
J 2
(-5985 2760);
DISPLAY 0.808511 (-5985 2760);
WIRE 16 -1 (-5975 2700)(-7500 2700);
FORCEPROP 2 LAST SIG_NAME UART_BIC_GF_RXD
J 2
(-5985 2710);
DISPLAY 0.808511 (-5985 2710);
WIRE 16 -1 (-7500 2600)(-5975 2600);
FORCEPROP 2 LAST SIG_NAME UART_SYS_DBG_TX
J 0
(-6560 2610);
DISPLAY 0.851064 (-6560 2610);
WIRE 16 -1 (-5975 2550)(-7500 2550);
FORCEPROP 2 LAST SIG_NAME UART_SYS_DBG_RX
J 0
(-6560 2560);
DISPLAY 0.851064 (-6560 2560);
WIRE 16 -1 (-5975 2450)(-7500 2450);
FORCEPROP 2 LAST SIG_NAME RST_SRST_PLD_BMC_R_N
J 0
(-6785 2460);
DISPLAY 0.851064 (-6785 2460);
WIRE 16 -1 (-7500 2300)(-5975 2300);
FORCEPROP 2 LAST SIG_NAME FM_SOL_UART_CH_SEL
J 0
(-6635 2310);
DISPLAY 0.808511 (-6635 2310);
WIRE 16 -1 (-7500 2100)(-5975 2100);
FORCEPROP 2 LAST SIG_NAME IRQ_BMC_LPC_SERIRQ_ESPI_GF
J 2
(-5950 2110);
DISPLAY 0.808511 (-5950 2110);
WIRE 16 -1 (-7500 1950)(-5975 1950);
FORCEPROP 2 LAST SIG_NAME ESPI_LPC_LAD1_IO1
J 0
(-6600 1960);
DISPLAY 0.808511 (-6600 1960);
WIRE 16 -1 (-7500 1900)(-5975 1900);
FORCEPROP 2 LAST SIG_NAME ESPI_LPC_LAD2_IO2
J 0
(-6600 1910);
DISPLAY 0.808511 (-6600 1910);
WIRE 16 -1 (-7500 1800)(-5975 1800);
FORCEPROP 2 LAST SIG_NAME LPC_ESPI_SEL
J 2
(-6025 1810);
DISPLAY 0.808511 (-6025 1810);
WIRE 16 -1 (-7500 1600)(-5975 1600);
FORCEPROP 2 LAST SIG_NAME SPI_SYS_R_MOSI
J 2
(-5950 1610);
DISPLAY 0.808511 (-5950 1610);
WIRE 16 -1 (-7500 1550)(-5975 1550);
FORCEPROP 2 LAST SIG_NAME SPI_SYS_R_MISO
J 2
(-5950 1560);
DISPLAY 0.808511 (-5950 1560);
WIRE 16 -1 (-5975 1250)(-7500 1250);
FORCEPROP 2 LAST SIG_NAME RMII_TXEN
J 2
(-5950 1260);
DISPLAY 0.808511 (-5950 1260);
WIRE 16 -1 (-5975 1200)(-7500 1200);
FORCEPROP 2 LAST SIG_NAME RMII_TXD0
J 2
(-5950 1210);
DISPLAY 0.808511 (-5950 1210);
WIRE 16 -1 (-5975 1100)(-7500 1100);
FORCEPROP 2 LAST SIG_NAME RMII_RXER
J 2
(-5950 1110);
DISPLAY 0.808511 (-5950 1110);
WIRE 16 -1 (-5975 1050)(-7500 1050);
FORCEPROP 2 LAST SIG_NAME RMII_RXD0
J 2
(-5950 1060);
DISPLAY 0.808511 (-5950 1060);
WIRE 16 -1 (-5975 900)(-7500 900);
FORCEPROP 2 LAST SIG_NAME PECI_BMC
J 2
(-5975 910);
DISPLAY 0.808511 (-5975 910);
WIRE 16 -1 (-7500 350)(-5975 350);
FORCEPROP 0 LAST SIG_NAME SGPIO_LD_1
J 2
(-5950 360);
DISPLAY 0.808511 (-5950 360);
WIRE 16 -1 (-5975 250)(-7500 250);
FORCEPROP 2 LAST SIG_NAME RST_SGPIO_RESET_N
J 2
(-5950 260);
DISPLAY 0.808511 (-5950 260);
WIRE 16 -1 (-7500 850)(-5975 850);
FORCEPROP 2 LAST SIG_NAME PVCCIO_PECI_BMC
J 2
(-5975 860);
DISPLAY 0.808511 (-5975 860);
WIRE 16 -1 (-5975 1150)(-7500 1150);
FORCEPROP 2 LAST SIG_NAME RMII_TXD1
J 2
(-5950 1160);
DISPLAY 0.808511 (-5950 1160);
WIRE 16 -1 (-7500 1650)(-5975 1650);
FORCEPROP 2 LAST SIG_NAME SPI_SYS_CS0_N
J 2
(-5950 1660);
DISPLAY 0.808511 (-5950 1660);
WIRE 16 -1 (-7500 1700)(-5975 1700);
FORCEPROP 2 LAST SIG_NAME SPI_SYS_R_CLK
J 2
(-5950 1710);
DISPLAY 0.808511 (-5950 1710);
WIRE 16 -1 (-7500 2000)(-5975 2000);
FORCEPROP 2 LAST SIG_NAME ESPI_LPC_LAD0_IO0
J 2
(-5960 2010);
DISPLAY 0.808511 (-5960 2010);
WIRE 16 -1 (-5975 2200)(-7500 2200);
FORCEPROP 2 LAST SIG_NAME ESPI_HOST_LPC_BMC_CLK
J 2
(-5950 2210);
DISPLAY 0.808511 (-5950 2210);
WIRE 16 -1 (-7500 2400)(-5975 2400);
FORCEPROP 2 LAST SIG_NAME SPI_TPM_CS_N
J 2
(-5985 2410);
DISPLAY 0.808511 (-5985 2410);
WIRE 16 -1 (-5475 2850)(-6325 2850);
FORCEPROP 2 LAST SIG_NAME FM_PRSNT_1_N
J 0
(-6060 2860);
DISPLAY 0.808511 (-6060 2860);
WIRE 16 -1 (-11125 2500)(-9050 2500);
FORCEPROP 2 LAST SIG_NAME I3C3_SPD_SDA
J 0
(-11125 2510);
DISPLAY 0.808511 (-11125 2510);
WIRE 16 -1 (-9050 2750)(-11125 2750);
FORCEPROP 2 LAST SIG_NAME I3C1_SPD_SCL
J 0
(-11125 2760);
DISPLAY 0.808511 (-11125 2760);
WIRE 16 -1 (-9050 2700)(-11125 2700);
FORCEPROP 2 LAST SIG_NAME I3C1_SPD_SDA
J 0
(-11125 2710);
DISPLAY 0.808511 (-11125 2710);
WIRE 16 -1 (-9050 2600)(-11125 2600);
FORCEPROP 2 LAST SIG_NAME I3C2_SPD_SDA
J 0
(-11125 2610);
DISPLAY 0.808511 (-11125 2610);
WIRE 16 -1 (-11125 2550)(-9050 2550);
FORCEPROP 2 LAST SIG_NAME I3C3_SPD_SCL
J 0
(-11125 2560);
DISPLAY 0.808511 (-11125 2560);
WIRE 16 -1 (-9050 2450)(-11125 2450);
FORCEPROP 2 LAST SIG_NAME I3C4_SPD_SCL
J 0
(-11125 2460);
DISPLAY 0.808511 (-11125 2460);
WIRE 16 -1 (-9050 2200)(-10250 2200);
FORCEPROP 2 LAST SIG_NAME SMB_BMC_MM14_R1_SCL
J 0
(-10035 2210);
DISPLAY 0.808511 (-10035 2210);
WIRE 16 -1 (-9050 2150)(-10250 2150);
FORCEPROP 2 LAST SIG_NAME SMB_BMC_MM14_R1_SDA
J 0
(-10035 2160);
DISPLAY 0.808511 (-10035 2160);
WIRE 16 -1 (-10450 2150)(-11125 2150);
FORCEPROP 2 LAST SIG_NAME SMB_BMC_MM14_SDA
J 0
(-11125 2160);
DISPLAY 0.808511 (-11125 2160);
WIRE 16 -1 (-10450 2200)(-11125 2200);
FORCEPROP 2 LAST SIG_NAME SMB_BMC_MM14_SCL
J 0
(-11125 2210);
DISPLAY 0.808511 (-11125 2210);
WIRE 16 -1 (-9050 2400)(-11125 2400);
FORCEPROP 2 LAST SIG_NAME I3C4_SPD_SDA
J 0
(-11125 2410);
DISPLAY 0.808511 (-11125 2410);
WIRE 16 -1 (-9050 2650)(-11125 2650);
FORCEPROP 2 LAST SIG_NAME I3C2_SPD_SCL
J 0
(-11125 2660);
DISPLAY 0.808511 (-11125 2660);
WIRE 16 -1 (-9050 -950)(-10025 -950);
FORCEPROP 2 LAST SIG_NAME TP_GF_A62
J 0
(-10025 -940);
DISPLAY 0.808511 (-10025 -940);
WIRE 16 -1 (-9050 -1000)(-10025 -1000);
FORCEPROP 2 LAST SIG_NAME TP_GF_A63
J 0
(-10025 -990);
DISPLAY 0.808511 (-10025 -990);
WIRE 16 -1 (-10425 -50)(-11125 -50);
FORCEPROP 2 LAST SIG_NAME PWRGD_PSU_AC_PWROK
J 0
(-11110 -40);
DISPLAY 0.808511 (-11110 -40);
WIRE 16 -1 (-5975 0)(-7500 0);
FORCEPROP 2 LAST SIG_NAME QSPI_2_PLD_CLK
J 2
(-5950 10);
DISPLAY 0.808511 (-5950 10);
WIRE 16 -1 (-9050 2300)(-11125 2300);
FORCEPROP 2 LAST SIG_NAME FM_VIRTUAL_RESEAT
J 0
(-11110 2310);
DISPLAY 0.808511 (-11110 2310);
WIRE 16 -1 (-5975 1000)(-7500 1000);
FORCEPROP 2 LAST SIG_NAME RMII_RXD1
J 2
(-5950 1010);
DISPLAY 0.808511 (-5950 1010);
WIRE 16 -1 (-5975 100)(-7500 100);
FORCEPROP 2 LAST SIG_NAME AC_PWR_BTN_N
J 2
(-5950 110);
DISPLAY 0.808511 (-5950 110);
WIRE 16 -1 (-5975 -100)(-7500 -100);
FORCEPROP 2 LAST SIG_NAME QSPI_2_PLD_IO0
J 2
(-5950 -90);
DISPLAY 0.808511 (-5950 -90);
WIRE 16 -1 (-5975 -150)(-7500 -150);
FORCEPROP 2 LAST SIG_NAME QSPI_2_PLD_IO1
J 2
(-5950 -140);
DISPLAY 0.808511 (-5950 -140);
WIRE 16 -1 (-5975 -250)(-7500 -250);
FORCEPROP 2 LAST SIG_NAME QSPI_2_PLD_IO3
J 2
(-5950 -240);
DISPLAY 0.808511 (-5950 -240);
WIRE 16 -1 (-5975 -350)(-7500 -350);
FORCEPROP 2 LAST SIG_NAME USB_HOST_BMC_B_DP
J 2
(-5950 -340);
DISPLAY 0.808511 (-5950 -340);
WIRE 16 -1 (-5975 -400)(-7500 -400);
FORCEPROP 2 LAST SIG_NAME USB_HOST_BMC_B_DN
J 2
(-5950 -390);
DISPLAY 0.808511 (-5950 -390);
WIRE 16 -1 (-5975 -550)(-7500 -550);
FORCEPROP 2 LAST SIG_NAME USB_HOST_BMC_A_DN
J 2
(-5950 -540);
DISPLAY 0.808511 (-5950 -540);
WIRE 16 -1 (-7500 -650)(-5975 -650);
FORCEPROP 2 LAST SIG_NAME USB_FPNL_DP
J 2
(-5960 -640);
DISPLAY 0.808511 (-5960 -640);
WIRE 16 -1 (-6275 -1475)(-7000 -1475);
FORCEPROP 2 LAST SIG_NAME FM_HDD_LED_N
J 2
(-6560 -1465);
DISPLAY 0.808511 (-6560 -1465);
WIRE 16 -1 (-7500 -1300)(-6550 -1300);
FORCEPROP 2 LAST SIG_NAME PCH_BEEP_R_LED
J 0
(-7260 -1290);
DISPLAY 0.851064 (-7260 -1290);
WIRE 16 -1 (-10450 2000)(-11125 2000);
FORCEPROP 2 LAST SIG_NAME SMB_BMC_MM2_SCL
J 0
(-11125 2010);
DISPLAY 0.808511 (-11125 2010);
WIRE 16 -1 (-10250 2000)(-9050 2000);
FORCEPROP 2 LAST SIG_NAME SMB_BMC_MM2_SCL_R1
J 0
(-10035 2010);
DISPLAY 0.851064 (-10035 2010);
WIRE 16 -1 (-9050 2050)(-11125 2050);
FORCEPROP 2 LAST SIG_NAME SMB_BMC_MM1_SDA
J 0
(-11125 2060);
DISPLAY 0.808511 (-11125 2060);
WIRE 16 -1 (-9050 2100)(-11125 2100);
FORCEPROP 2 LAST SIG_NAME SMB_BMC_MM1_SCL
J 0
(-11125 2110);
DISPLAY 0.808511 (-11125 2110);
WIRE 16 -1 (-11125 1700)(-9050 1700);
FORCEPROP 2 LAST SIG_NAME SMB_BMC_MM5_SCL
J 0
(-11135 1710);
DISPLAY 0.851064 (-11135 1710);
WIRE 16 -1 (-9050 1950)(-11125 1950);
FORCEPROP 2 LAST SIG_NAME SMB_BMC_MM2_SDA
J 0
(-11125 1960);
DISPLAY 0.808511 (-11125 1960);
WIRE 16 -1 (-9050 1750)(-11125 1750);
FORCEPROP 2 LAST SIG_NAME SMB_BMC_MM4_SDA
J 0
(-11125 1760);
DISPLAY 0.808511 (-11125 1760);
WIRE 16 -1 (-11125 1650)(-9050 1650);
FORCEPROP 2 LAST SIG_NAME SMB_BMC_MM5_SDA
J 0
(-11135 1660);
DISPLAY 0.851064 (-11135 1660);
WIRE 16 -1 (-9050 1550)(-11125 1550);
FORCEPROP 2 LAST SIG_NAME CLK_100M_PCH_DP
J 0
(-11135 1560);
DISPLAY 0.851064 (-11135 1560);
WIRE 16 -1 (-9050 1500)(-11125 1500);
FORCEPROP 2 LAST SIG_NAME CLK_100M_PCH_DN
J 0
(-11135 1510);
DISPLAY 0.851064 (-11135 1510);
WIRE 16 -1 (-9050 1200)(-10825 1200);
FORCEPROP 2 LAST SIG_NAME P2E_PCH_TX_C_DN
J 0
(-10835 1210);
DISPLAY 0.851064 (-10835 1210);
WIRE 16 -1 (-9050 1250)(-10825 1250);
FORCEPROP 2 LAST SIG_NAME P2E_PCH_TX_C_DP
J 0
(-10835 1260);
DISPLAY 0.851064 (-10835 1260);
WIRE 16 -1 (-10825 1400)(-9050 1400);
FORCEPROP 2 LAST SIG_NAME P2E_PCH_RX_DP
J 0
(-10835 1410);
DISPLAY 0.851064 (-10835 1410);
WIRE 16 -1 (-10825 1350)(-9050 1350);
FORCEPROP 2 LAST SIG_NAME P2E_PCH_RX_DN
J 0
(-10835 1360);
DISPLAY 0.851064 (-10835 1360);
WIRE 16 -1 (-9050 1100)(-11125 1100);
FORCEPROP 2 LAST SIG_NAME SMB_BMC_MM6_SCL
J 0
(-11125 1110);
DISPLAY 0.808511 (-11125 1110);
WIRE 16 -1 (-9050 1050)(-11125 1050);
FORCEPROP 2 LAST SIG_NAME SMB_BMC_MM6_SDA
J 0
(-11125 1060);
DISPLAY 0.808511 (-11125 1060);
WIRE 16 -1 (-9050 1000)(-11125 1000);
FORCEPROP 2 LAST SIG_NAME SMB_BMC_MM7_SCL
J 0
(-11125 1010);
DISPLAY 0.808511 (-11125 1010);
WIRE 16 -1 (-9050 950)(-11125 950);
FORCEPROP 2 LAST SIG_NAME SMB_BMC_MM7_SDA
J 0
(-11125 960);
DISPLAY 0.808511 (-11125 960);
WIRE 16 -1 (-9050 900)(-11125 900);
FORCEPROP 2 LAST SIG_NAME SMB_BMC_MM8_SCL
J 0
(-11135 910);
DISPLAY 0.808511 (-11135 910);
WIRE 16 -1 (-9050 750)(-11125 750);
FORCEPROP 2 LAST SIG_NAME SMB_BMC_MM9_SCL
J 0
(-11125 760);
DISPLAY 0.808511 (-11125 760);
WIRE 16 -1 (-9050 850)(-11125 850);
FORCEPROP 2 LAST SIG_NAME SMB_BMC_MM8_SDA
J 0
(-11125 860);
DISPLAY 0.808511 (-11125 860);
WIRE 16 -1 (-9050 500)(-11125 500);
FORCEPROP 2 LAST SIG_NAME JTAG_MB_TCK
J 0
(-11135 510);
DISPLAY 0.808511 (-11135 510);
WIRE 16 -1 (-9050 450)(-11125 450);
FORCEPROP 2 LAST SIG_NAME JTAG_MB_TMS
J 0
(-11135 460);
DISPLAY 0.808511 (-11135 460);
WIRE 16 -1 (-9050 -50)(-10225 -50);
FORCEPROP 2 LAST SIG_NAME PWRGD_PSU_AC_PWROK_R
J 0
(-10085 -40);
DISPLAY 0.808511 (-10085 -40);
WIRE 16 -1 (-11125 -650)(-9050 -650);
FORCEPROP 2 LAST SIG_NAME IRQ_SMI_ACTIVE_GF_N
J 0
(-11125 -640);
DISPLAY 0.808511 (-11125 -640);
WIRE 16 -1 (-9050 -550)(-11125 -550);
FORCEPROP 2 LAST SIG_NAME FM_INTRUDER_N
J 0
(-11125 -540);
DISPLAY 0.808511 (-11125 -540);
WIRE 16 -1 (-11125 -500)(-9050 -500);
FORCEPROP 2 LAST SIG_NAME RST_ROT_CPU_N
J 0
(-11125 -490);
DISPLAY 0.808511 (-11125 -490);
WIRE 16 -1 (-11125 -450)(-9050 -450);
FORCEPROP 2 LAST SIG_NAME FM_BMC_UARTSW_MSB_N
J 0
(-11110 -440);
DISPLAY 0.851064 (-11110 -440);
WIRE 16 -1 (-9050 -400)(-11125 -400);
FORCEPROP 2 LAST SIG_NAME RST_PLTRST_N
J 0
(-11125 -390);
DISPLAY 0.808511 (-11125 -390);
WIRE 16 -1 (-9050 -350)(-11125 -350);
FORCEPROP 2 LAST SIG_NAME FM_DBP_BMC_PRDY_N
J 0
(-11125 -340);
DISPLAY 0.808511 (-11125 -340);
WIRE 16 -1 (-9050 -300)(-11125 -300);
FORCEPROP 2 LAST SIG_NAME FM_DBP_CPU_PREQ_GF_R_N
J 0
(-11125 -290);
DISPLAY 0.808511 (-11125 -290);
WIRE 16 -1 (-9050 -250)(-11125 -250);
FORCEPROP 2 LAST SIG_NAME PWRGD_SYS_PWROK
J 0
(-11110 -240);
DISPLAY 0.808511 (-11110 -240);
WIRE 16 -1 (-9050 -200)(-11125 -200);
FORCEPROP 2 LAST SIG_NAME SYS_PWRBTN_N
J 0
(-11125 -190);
DISPLAY 0.808511 (-11125 -190);
WIRE 16 -1 (-9050 -150)(-11125 -150);
FORCEPROP 2 LAST SIG_NAME RST_MB_STBY_N
J 0
(-11125 -140);
DISPLAY 0.808511 (-11125 -140);
WIRE 16 -1 (-9050 -100)(-10025 -100);
FORCEPROP 2 LAST SIG_NAME TP_GF_A45
J 0
(-10025 -90);
DISPLAY 0.808511 (-10025 -90);
WIRE 16 -1 (-9050 400)(-11125 400);
FORCEPROP 2 LAST SIG_NAME JTAG_MB_TDI
J 0
(-11135 410);
DISPLAY 0.808511 (-11135 410);
WIRE 16 -1 (-9050 350)(-11125 350);
FORCEPROP 2 LAST SIG_NAME JTAG_MB_TDO
J 0
(-11135 360);
DISPLAY 0.808511 (-11135 360);
WIRE 16 -1 (-9050 300)(-11125 300);
FORCEPROP 2 LAST SIG_NAME SMB_BMC_MM12_SCL
J 0
(-11125 310);
DISPLAY 0.808511 (-11125 310);
WIRE 16 -1 (-9050 250)(-11125 250);
FORCEPROP 2 LAST SIG_NAME SMB_BMC_MM12_SDA
J 0
(-11125 260);
DISPLAY 0.808511 (-11125 260);
WIRE 16 -1 (-9050 200)(-11125 200);
FORCEPROP 2 LAST SIG_NAME SMB_BMC_MM13_SCL
J 0
(-11125 210);
DISPLAY 0.808511 (-11125 210);
WIRE 16 -1 (-9050 150)(-11125 150);
FORCEPROP 2 LAST SIG_NAME SMB_BMC_MM13_SDA
J 0
(-11125 160);
DISPLAY 0.808511 (-11125 160);
WIRE 16 -1 (-9050 0)(-11125 0);
FORCEPROP 2 LAST SIG_NAME FM_JTAG_SEL
J 0
(-11125 10);
DISPLAY 0.808511 (-11125 10);
WIRE 16 -1 (-11125 -600)(-9050 -600);
FORCEPROP 2 LAST SIG_NAME FM_BMC_UARTSW_LSB_N
J 0
(-11110 -590);
DISPLAY 0.851064 (-11110 -590);
WIRE 16 -1 (-11125 -700)(-9050 -700);
FORCEPROP 2 LAST SIG_NAME FM_PRSNT_1_N
J 0
(-11110 -690);
DISPLAY 0.808511 (-11110 -690);
WIRE 16 -1 (-9050 -800)(-11125 -800);
FORCEPROP 2 LAST SIG_NAME USB3_FPNL_RXP
J 2
(-10610 -790);
DISPLAY 0.808511 (-10610 -790);
WIRE 16 -1 (-9050 -850)(-11125 -850);
FORCEPROP 2 LAST SIG_NAME USB3_FPNL_RXN
J 2
(-10610 -840);
DISPLAY 0.808511 (-10610 -840);
WIRE 16 -1 (-9050 -1300)(-11150 -1300);
FORCEPROP 2 LAST SIG_NAME CLK_100M_GPU_DN
J 0
(-11110 -1290);
DISPLAY 0.851064 (-11110 -1290);
WIRE 16 -1 (-9050 -1250)(-11150 -1250);
FORCEPROP 2 LAST SIG_NAME CLK_100M_GPU_DP
J 0
(-11110 -1240);
DISPLAY 0.851064 (-11110 -1240);
WIRE 16 -1 (-9050 -1150)(-11150 -1150);
FORCEPROP 2 LAST SIG_NAME P2E_GPU_RX_DN
J 0
(-11110 -1140);
DISPLAY 0.851064 (-11110 -1140);
WIRE 16 -1 (-9050 -1100)(-11150 -1100);
FORCEPROP 2 LAST SIG_NAME P2E_GPU_RX_DP
J 0
(-11110 -1090);
DISPLAY 0.851064 (-11110 -1090);
WIRE 16 -1 (-9050 600)(-11125 600);
FORCEPROP 2 LAST SIG_NAME SMB_BMC_MM10_SDA
J 0
(-11125 610);
DISPLAY 0.808511 (-11125 610);
WIRE 16 -1 (-9050 700)(-11125 700);
FORCEPROP 2 LAST SIG_NAME SMB_BMC_MM9_SDA
J 0
(-11125 710);
DISPLAY 0.808511 (-11125 710);
WIRE 16 -1 (-9050 650)(-11125 650);
FORCEPROP 2 LAST SIG_NAME SMB_BMC_MM10_SCL
J 0
(-11135 660);
DISPLAY 0.808511 (-11135 660);
WIRE 16 -1 (-7500 1850)(-5975 1850);
FORCEPROP 2 LAST SIG_NAME ESPI_LPC_LAD3_IO3
J 0
(-6600 1860);
DISPLAY 0.808511 (-6600 1860);
WIRE 16 -1 (-7500 2050)(-5975 2050);
FORCEPROP 2 LAST SIG_NAME RST_BMC_LPC_ESPI_N
J 2
(-5950 2060);
DISPLAY 0.808511 (-5950 2060);
WIRE 16 -1 (-5975 2150)(-7500 2150);
FORCEPROP 2 LAST SIG_NAME ESPI_HOST_LPC_BMC_LFRAME_N
J 2
(-5950 2160);
DISPLAY 0.808511 (-5950 2160);
WIRE 16 -1 (-5975 2350)(-7500 2350);
FORCEPROP 2 LAST SIG_NAME H_CPU_CATERR_LVC2_R2_N
J 0
(-6860 2360);
DISPLAY 0.851064 (-6860 2360);
DOT 1 (-5675 -1250);
DOT 1 (-5625 -1300);
DOT 1 (-9300 -900);
DOT 1 (-9300 1300);
DOT 1 (-7300 950);
DOT 1 (-7300 2650);
DOT 1 (-7300 1400);
DOT 1 (-9300 -750);
DOT 1 (-9300 1150);
DOT 1 (-9300 100);
DOT 1 (-9300 550);
DOT 1 (-7300 550);
DOT 1 (-9300 2350);
DOT 1 (-9300 2800);
DOT 1 (-9300 2950);
DOT 1 (-9300 -1350);
DOT 1 (-9300 -1200);
DOT 1 (-7300 -1050);
DOT 1 (-7300 -750);
DOT 1 (-7300 -600);
DOT 1 (-7300 -450);
DOT 1 (-9800 3575);
DOT 1 (-10225 3575);
DOT 1 (-10225 3100);
DOT 1 (-4675 150);
DOT 1 (-7300 -900);
DOT 1 (-7300 300);
DOT 1 (-7300 -300);
DOT 1 (-7300 2950);
DOT 1 (-9300 1450);
DOT 1 (-9300 -1050);
DOT 1 (-7300 -1200);
DOT 1 (-7300 1750);
DOT 1 (-7300 -1350);
DOT 1 (-9300 1600);
DOT 1 (-7300 2500);
FORCENOTE
(UNSTUFFED THE SERIES RES)
(-5500 -500) 0;
DISPLAY LEFT (-5500 -500);
DISPLAY 1.021277 (-5500 -500);
PAINT WHITE (-5500 -500);
QUIT
